G04 ================== begin FILE IDENTIFICATION RECORD ==================*
G04 Layout Name:  t6mg_pdb_a_v02_0109_1330.brd*
G04 Film Name:    panel*
G04 File Format:  Gerber RS274X*
G04 File Origin:  Cadence Allegro 16.3-S038*
G04 Origin Date:  Mon Jan 13 14:11:54 2014*
G04 *
G04 Layer:  MANUFACTURING/PHOTOPLOT_OUTLINE*
G04 Layer:  DRAWING FORMAT/TITLE_BLOCK*
G04 Layer:  DRAWING FORMAT/TITLE_DATA_PANEL*
G04 Layer:  BOARD GEOMETRY/ASSEMBLY_NOTES*
G04 *
G04 Offset:    (0.00 0.00)*
G04 Mirror:    No*
G04 Mode:      Positive*
G04 Rotation:  0*
G04 FullContactRelief:  No*
G04 UndefLineWidth:     6.00*
G04 ================== end FILE IDENTIFICATION RECORD ====================*
%FSLAX25Y25*MOIN*%
%IR0*IPPOS*OFA0.00000B0.00000*MIA0B0*SFA1.00000B1.00000*%
%ADD10C,.006*%
G75*
%LPD*%
G75*
G36*
G01X773475Y1883734D02*
G02I-1969J0D01*
G37*
G54D10*
G01X-723776Y2987387D02*
Y-376795D01*
Y-489221D01*
X1782976D01*
Y-376795D01*
Y2987387D01*
X-723776D01*
G01X-112205Y2086614D02*
X-405512D01*
G03X-413386Y2078740I0J-7874D01*
G01Y7874D01*
G03X-405512Y0I7874J0D01*
G01X-112205D01*
G03X-106299Y5905I0J5906D01*
G01Y9842D01*
G02X-100394Y15748I5905J1D01*
G01X-13780D01*
G03X-7874Y21653I1J5905D01*
G01Y2064960D01*
G03X-13780Y2070866I-5906J0D01*
G01X-100394D01*
G02X-106299Y2076771I0J5905D01*
G01Y2080708D01*
G03X-112205Y2086614I-5906J0D01*
G01X-413386Y2081740D02*
Y2122967D01*
G01X-77037Y2119967D02*
X-413386D01*
G01X-408386Y2120967D02*
X-413386Y2119967D01*
X-408386Y2118967D01*
Y2120967D01*
G01X-352403Y939713D02*
X-98451D01*
Y1481750D01*
G01X-241811Y1139713D02*
X-98451D01*
G01X-24487Y2119967D02*
X405512D01*
G01X-4000Y-62500D02*
Y-137500D01*
X496000D01*
Y-62500D01*
X-4000D01*
G01X104331Y0D02*
X397638D01*
G03X405512Y7874I0J7874D01*
G01Y2078740D01*
G03X397638Y2086614I-7874J0D01*
G01X104331D01*
G03X98425Y2080709I0J-5906D01*
G01Y2076772D01*
G02X92520Y2070866I-5905J-1D01*
G01X5906D01*
G03X0Y2064961I-1J-5905D01*
G01Y21654D01*
G03X5906Y15748I5906J0D01*
G01X92520D01*
G02X98425Y9843I0J-5905D01*
G01Y5906D01*
G03X104331Y0I5906J0D01*
G01X-7874Y116184D02*
G02X0I3937J0D01*
G01X-7874Y135870D02*
G03X0I3937J0D01*
G01X-7874Y279584D02*
G02X0I3937J0D01*
G01X-7874Y299270D02*
G03X0I3937J0D01*
G01X-7874Y462534D02*
G03X0I3937J0D01*
G01X-7874Y442848D02*
G02X0I3937J0D01*
G01X-7874Y606272D02*
G02X0I3937J0D01*
G01X-7874Y625958D02*
G03X0I3937J0D01*
G01X-7874Y769584D02*
G02X0I3937J0D01*
G01X-7874Y789270D02*
G03X0I3937J0D01*
G01X-7874Y952670D02*
G03X0I3937J0D01*
G01X-7874Y932984D02*
G02X0I3937J0D01*
G01X-7874Y1096248D02*
G02X0I3937J0D01*
G01X-7874Y1115934D02*
G03X0I3937J0D01*
G01X-7874Y1259672D02*
G02X0I3937J0D01*
G01X-7874Y1279358D02*
G03X0I3937J0D01*
G01X-7874Y1432984D02*
G02X0I3937J0D01*
G01X-7874Y1452670D02*
G03X0I3937J0D01*
G01X-7874Y1596248D02*
G02X0I3937J0D01*
G01X-7874Y1615934D02*
G03X0I3937J0D01*
G01X-7874Y1759672D02*
G02X0I3937J0D01*
G01X-7874Y1779358D02*
G03X0I3937J0D01*
G01X-7874Y1950848D02*
G02X0I3937J0D01*
G01X-7874Y1970534D02*
G03X0I3937J0D01*
G01X8000Y-127500D02*
Y-132500D01*
G01X6543Y-127500D02*
X9457D01*
G01X14367Y-132500D02*
X11833D01*
Y-127500D01*
X14367D01*
G01X13353Y-129917D02*
X11833D01*
G01X16933Y-127500D02*
Y-132500D01*
X19467D01*
G01X23300Y-132667D02*
X23173Y-132583D01*
Y-132417D01*
X23300Y-132333D01*
X23427Y-132417D01*
Y-132583D01*
X23300Y-132667D01*
G01Y-130417D02*
X23173Y-130333D01*
Y-130167D01*
X23300Y-130083D01*
X23427Y-130167D01*
Y-130333D01*
X23300Y-130417D01*
G01X28083Y-134167D02*
X27450Y-133333D01*
X27133Y-132500D01*
Y-129167D01*
X27450Y-128333D01*
X28083Y-127500D01*
G01X33500D02*
X32993Y-127667D01*
X32613Y-128083D01*
X32360Y-128583D01*
X32170Y-129250D01*
X32107Y-130000D01*
X32170Y-130750D01*
X32360Y-131417D01*
X32613Y-131917D01*
X32993Y-132333D01*
X33500Y-132500D01*
X34007Y-132333D01*
X34387Y-131917D01*
X34640Y-131417D01*
X34830Y-130750D01*
X34893Y-130000D01*
X34830Y-129250D01*
X34640Y-128583D01*
X34387Y-128083D01*
X34007Y-127667D01*
X33500Y-127500D01*
G01X37207Y-131500D02*
X37587Y-132083D01*
X38093Y-132417D01*
X38663Y-132500D01*
X39170Y-132417D01*
X39677Y-132000D01*
X39993Y-131500D01*
X40057Y-131000D01*
X39930Y-130417D01*
X39487Y-130000D01*
X39043Y-129833D01*
X38473D01*
G01X39043D02*
X39423Y-129583D01*
X39740Y-129167D01*
X39867Y-128667D01*
X39740Y-128167D01*
X39423Y-127750D01*
X38853Y-127500D01*
X38283Y-127583D01*
X37713Y-127917D01*
G01X44017Y-134167D02*
X44650Y-133333D01*
X44967Y-132500D01*
Y-129167D01*
X44650Y-128333D01*
X44017Y-127500D01*
G01X47407Y-131500D02*
X47787Y-132083D01*
X48293Y-132417D01*
X48863Y-132500D01*
X49370Y-132417D01*
X49877Y-132000D01*
X50193Y-131500D01*
X50257Y-131000D01*
X50130Y-130417D01*
X49687Y-130000D01*
X49243Y-129833D01*
X48673D01*
G01X49243D02*
X49623Y-129583D01*
X49940Y-129167D01*
X50067Y-128667D01*
X49940Y-128167D01*
X49623Y-127750D01*
X49053Y-127500D01*
X48483Y-127583D01*
X47913Y-127917D01*
G01X52697Y-128333D02*
X53077Y-127833D01*
X53520Y-127583D01*
X54027Y-127500D01*
X54660Y-127667D01*
X55103Y-128083D01*
X55230Y-128583D01*
X55167Y-129083D01*
X54913Y-129500D01*
X53647Y-130333D01*
X53077Y-130917D01*
X52697Y-131750D01*
X52570Y-132500D01*
X55230D01*
G01X58873D02*
X59000Y-131417D01*
X59190Y-130500D01*
X59443Y-129667D01*
X59760Y-128750D01*
X60267Y-127500D01*
X57733D01*
G01X63277Y-130833D02*
X64923D01*
G01X67997Y-128333D02*
X68377Y-127833D01*
X68820Y-127583D01*
X69327Y-127500D01*
X69960Y-127667D01*
X70403Y-128083D01*
X70530Y-128583D01*
X70467Y-129083D01*
X70213Y-129500D01*
X68947Y-130333D01*
X68377Y-130917D01*
X67997Y-131750D01*
X67870Y-132500D01*
X70530D01*
G01X72907Y-131500D02*
X73287Y-132083D01*
X73793Y-132417D01*
X74363Y-132500D01*
X74870Y-132417D01*
X75377Y-132000D01*
X75693Y-131500D01*
X75757Y-131000D01*
X75630Y-130417D01*
X75187Y-130000D01*
X74743Y-129833D01*
X74173D01*
G01X74743D02*
X75123Y-129583D01*
X75440Y-129167D01*
X75567Y-128667D01*
X75440Y-128167D01*
X75123Y-127750D01*
X74553Y-127500D01*
X73983Y-127583D01*
X73413Y-127917D01*
G01X80160Y-132500D02*
Y-127500D01*
X77817Y-131083D01*
X80983D01*
G01X83107Y-131750D02*
X83487Y-132167D01*
X83930Y-132417D01*
X84500Y-132500D01*
X85070Y-132333D01*
X85513Y-132000D01*
X85830Y-131417D01*
X85893Y-130750D01*
X85767Y-130083D01*
X85450Y-129667D01*
X85007Y-129333D01*
X84563Y-129250D01*
X84120Y-129333D01*
X83550Y-129667D01*
X83740Y-127500D01*
X85450D01*
G01X93497Y-132500D02*
Y-127500D01*
X95903D01*
G01X95017Y-129917D02*
X93497D01*
G01X98217Y-132500D02*
X99800Y-127500D01*
X101383Y-132500D01*
G01X100813Y-130750D02*
X98787D01*
G01X103570Y-132500D02*
X106230Y-127500D01*
G01X103570D02*
X106230Y-132500D01*
G01X110000Y-132667D02*
X109873Y-132583D01*
Y-132417D01*
X110000Y-132333D01*
X110127Y-132417D01*
Y-132583D01*
X110000Y-132667D01*
G01Y-130417D02*
X109873Y-130333D01*
Y-130167D01*
X110000Y-130083D01*
X110127Y-130167D01*
Y-130333D01*
X110000Y-130417D01*
G01X114783Y-134167D02*
X114150Y-133333D01*
X113833Y-132500D01*
Y-129167D01*
X114150Y-128333D01*
X114783Y-127500D01*
G01X120200D02*
X119693Y-127667D01*
X119313Y-128083D01*
X119060Y-128583D01*
X118870Y-129250D01*
X118807Y-130000D01*
X118870Y-130750D01*
X119060Y-131417D01*
X119313Y-131917D01*
X119693Y-132333D01*
X120200Y-132500D01*
X120707Y-132333D01*
X121087Y-131917D01*
X121340Y-131417D01*
X121530Y-130750D01*
X121593Y-130000D01*
X121530Y-129250D01*
X121340Y-128583D01*
X121087Y-128083D01*
X120707Y-127667D01*
X120200Y-127500D01*
G01X123907Y-131500D02*
X124287Y-132083D01*
X124793Y-132417D01*
X125363Y-132500D01*
X125870Y-132417D01*
X126377Y-132000D01*
X126693Y-131500D01*
X126757Y-131000D01*
X126630Y-130417D01*
X126187Y-130000D01*
X125743Y-129833D01*
X125173D01*
G01X125743D02*
X126123Y-129583D01*
X126440Y-129167D01*
X126567Y-128667D01*
X126440Y-128167D01*
X126123Y-127750D01*
X125553Y-127500D01*
X124983Y-127583D01*
X124413Y-127917D01*
G01X130717Y-134167D02*
X131350Y-133333D01*
X131667Y-132500D01*
Y-129167D01*
X131350Y-128333D01*
X130717Y-127500D01*
G01X134107Y-131500D02*
X134487Y-132083D01*
X134993Y-132417D01*
X135563Y-132500D01*
X136070Y-132417D01*
X136577Y-132000D01*
X136893Y-131500D01*
X136957Y-131000D01*
X136830Y-130417D01*
X136387Y-130000D01*
X135943Y-129833D01*
X135373D01*
G01X135943D02*
X136323Y-129583D01*
X136640Y-129167D01*
X136767Y-128667D01*
X136640Y-128167D01*
X136323Y-127750D01*
X135753Y-127500D01*
X135183Y-127583D01*
X134613Y-127917D01*
G01X139523Y-131917D02*
X139967Y-132333D01*
X140473Y-132500D01*
X140980Y-132333D01*
X141423Y-131833D01*
X141740Y-131083D01*
X141867Y-130333D01*
Y-129417D01*
X141740Y-128667D01*
X141423Y-128000D01*
X141043Y-127667D01*
X140600Y-127500D01*
X140093Y-127667D01*
X139713Y-128000D01*
X139460Y-128500D01*
X139333Y-129167D01*
X139460Y-129750D01*
X139777Y-130333D01*
X140157Y-130667D01*
X140600Y-130750D01*
X141107Y-130583D01*
X141487Y-130167D01*
X141867Y-129417D01*
G01X145573Y-132500D02*
X145700Y-131417D01*
X145890Y-130500D01*
X146143Y-129667D01*
X146460Y-128750D01*
X146967Y-127500D01*
X144433D01*
G01X149977Y-130833D02*
X151623D01*
G01X154507Y-131500D02*
X154887Y-132083D01*
X155393Y-132417D01*
X155963Y-132500D01*
X156470Y-132417D01*
X156977Y-132000D01*
X157293Y-131500D01*
X157357Y-131000D01*
X157230Y-130417D01*
X156787Y-130000D01*
X156343Y-129833D01*
X155773D01*
G01X156343D02*
X156723Y-129583D01*
X157040Y-129167D01*
X157167Y-128667D01*
X157040Y-128167D01*
X156723Y-127750D01*
X156153Y-127500D01*
X155583Y-127583D01*
X155013Y-127917D01*
G01X159797Y-130417D02*
X160240Y-129833D01*
X160620Y-129500D01*
X161127Y-129333D01*
X161570Y-129500D01*
X161887Y-129833D01*
X162140Y-130333D01*
X162203Y-130917D01*
X162140Y-131417D01*
X161887Y-131917D01*
X161507Y-132333D01*
X161063Y-132500D01*
X160557Y-132333D01*
X160113Y-131833D01*
X159860Y-131083D01*
X159797Y-130250D01*
X159923Y-129167D01*
X160113Y-128583D01*
X160430Y-128000D01*
X160873Y-127583D01*
X161317Y-127500D01*
X161760Y-127667D01*
X162077Y-128083D01*
G01X166100Y-132500D02*
Y-127500D01*
X165340Y-128500D01*
G01Y-132500D02*
X166860D01*
G01X171960D02*
Y-127500D01*
X169617Y-131083D01*
X172783D01*
G01X332992Y1474272D02*
X79040D01*
Y932235D01*
G01X222400Y1274272D02*
X79040D01*
G01X191000Y-62500D02*
Y-137500D01*
G01Y-112500D02*
X294000D01*
Y-87500D01*
G01X191000D02*
X294000D01*
G01X301507Y-122500D02*
Y-117500D01*
X302773D01*
X303280Y-117750D01*
X303660Y-118083D01*
X303977Y-118583D01*
X304230Y-119167D01*
X304293Y-120000D01*
X304230Y-120833D01*
X303977Y-121417D01*
X303660Y-121917D01*
X303280Y-122250D01*
X302773Y-122500D01*
X301507D01*
G01X306417D02*
X308000Y-117500D01*
X309583Y-122500D01*
G01X309013Y-120750D02*
X306987D01*
G01X313100Y-117500D02*
Y-122500D01*
G01X311643Y-117500D02*
X314557D01*
G01X319467Y-122500D02*
X316933D01*
Y-117500D01*
X319467D01*
G01X318453Y-119917D02*
X316933D01*
G01X323300Y-122667D02*
X323173Y-122583D01*
Y-122417D01*
X323300Y-122333D01*
X323427Y-122417D01*
Y-122583D01*
X323300Y-122667D01*
G01Y-120417D02*
X323173Y-120333D01*
Y-120167D01*
X323300Y-120083D01*
X323427Y-120167D01*
Y-120333D01*
X323300Y-120417D01*
G01X296000Y-62500D02*
Y-137500D01*
G01X294000Y-62500D02*
Y-137500D01*
G01X301633Y-97500D02*
Y-92500D01*
X303153D01*
X303660Y-92750D01*
X304040Y-93333D01*
X304167Y-94000D01*
X304040Y-94667D01*
X303723Y-95167D01*
X303153Y-95417D01*
X301633D01*
G01X306860Y-97667D02*
X309140Y-92500D01*
G01X311643Y-97500D02*
Y-92500D01*
X314557Y-97500D01*
Y-92500D01*
G01X318200Y-97667D02*
X318073Y-97583D01*
Y-97417D01*
X318200Y-97333D01*
X318327Y-97417D01*
Y-97583D01*
X318200Y-97667D01*
G01Y-95417D02*
X318073Y-95333D01*
Y-95167D01*
X318200Y-95083D01*
X318327Y-95167D01*
Y-95333D01*
X318200Y-95417D01*
G01X296000Y-112500D02*
X496000D01*
G01X301633Y-72500D02*
Y-67500D01*
X303153D01*
X303660Y-67750D01*
X304040Y-68333D01*
X304167Y-69000D01*
X304040Y-69667D01*
X303723Y-70167D01*
X303153Y-70417D01*
X301633D01*
G01X306733Y-72500D02*
Y-67500D01*
X308317D01*
X308823Y-67750D01*
X309140Y-68083D01*
X309267Y-68750D01*
X309140Y-69417D01*
X308760Y-69833D01*
X308317Y-70083D01*
X306733D01*
G01X308317D02*
X309267Y-72500D01*
G01X313100D02*
X312593Y-72417D01*
X312150Y-72083D01*
X311770Y-71583D01*
X311517Y-71000D01*
X311390Y-70333D01*
Y-69667D01*
X311517Y-69000D01*
X311770Y-68417D01*
X312150Y-67917D01*
X312593Y-67583D01*
X313100Y-67500D01*
X313607Y-67583D01*
X314050Y-67917D01*
X314430Y-68417D01*
X314683Y-69000D01*
X314810Y-69667D01*
Y-70333D01*
X314683Y-71000D01*
X314430Y-71583D01*
X314050Y-72083D01*
X313607Y-72417D01*
X313100Y-72500D01*
G01X316933Y-71500D02*
X317250Y-72000D01*
X317630Y-72333D01*
X318073Y-72500D01*
X318580Y-72333D01*
X318960Y-72000D01*
X319340Y-71500D01*
X319467Y-70833D01*
Y-67500D01*
G01X324567Y-72500D02*
X322033D01*
Y-67500D01*
X324567D01*
G01X323553Y-69917D02*
X322033D01*
G01X329793Y-67917D02*
X329413Y-67667D01*
X328970Y-67500D01*
X328463D01*
X327893Y-67750D01*
X327450Y-68167D01*
X327133Y-68667D01*
X326880Y-69500D01*
X326817Y-70250D01*
X326943Y-71000D01*
X327133Y-71500D01*
X327513Y-72000D01*
X327957Y-72333D01*
X328400Y-72500D01*
X328843D01*
X329287Y-72333D01*
X329667Y-72083D01*
X329983Y-71750D01*
G01X333500Y-67500D02*
Y-72500D01*
G01X332043Y-67500D02*
X334957D01*
G01X338600Y-72667D02*
X338473Y-72583D01*
Y-72417D01*
X338600Y-72333D01*
X338727Y-72417D01*
Y-72583D01*
X338600Y-72667D01*
G01Y-70417D02*
X338473Y-70333D01*
Y-70167D01*
X338600Y-70083D01*
X338727Y-70167D01*
Y-70333D01*
X338600Y-70417D01*
G01X296000Y-87500D02*
X496000D01*
G01X411000Y-112500D02*
Y-137500D01*
G01X400638Y0D02*
X496239D01*
G01X405512Y2081740D02*
Y2122967D01*
G01X400638Y2086614D02*
X496239D01*
G01X400512Y2118967D02*
X405512Y2119967D01*
X400512Y2120967D01*
Y2118967D01*
G01X416633Y-122500D02*
Y-117500D01*
X418217D01*
X418723Y-117750D01*
X419040Y-118083D01*
X419167Y-118750D01*
X419040Y-119417D01*
X418660Y-119833D01*
X418217Y-120083D01*
X416633D01*
G01X418217D02*
X419167Y-122500D01*
G01X424267D02*
X421733D01*
Y-117500D01*
X424267D01*
G01X423253Y-119917D02*
X421733D01*
G01X426517Y-117500D02*
X428100Y-122500D01*
X429683Y-117500D01*
G01X433200Y-122667D02*
X433073Y-122583D01*
Y-122417D01*
X433200Y-122333D01*
X433327Y-122417D01*
Y-122583D01*
X433200Y-122667D01*
G01Y-120417D02*
X433073Y-120333D01*
Y-120167D01*
X433200Y-120083D01*
X433327Y-120167D01*
Y-120333D01*
X433200Y-120417D01*
G01X460000Y-112500D02*
Y-137500D01*
G01X493239Y1010054D02*
Y0D01*
G01X492239Y5000D02*
X493239Y0D01*
X494239Y5000D01*
X492239D01*
G01X493239Y1068904D02*
Y2086614D01*
G01X494239Y2081614D02*
X493239Y2086614D01*
X492239Y2081614D01*
X494239D01*
G01X744228Y1845063D02*
X744481Y1845313D01*
X744671Y1845729D01*
X744798Y1846313D01*
X744671Y1846813D01*
X744418Y1847146D01*
X743974Y1847396D01*
X742264D01*
Y1842396D01*
X744354D01*
X744798Y1842729D01*
X745051Y1843229D01*
X745178Y1843813D01*
X745051Y1844396D01*
X744671Y1844896D01*
X744228Y1845063D01*
X742264D01*
G01X747934Y1842396D02*
Y1845729D01*
G01Y1845063D02*
X748251Y1845396D01*
X748568Y1845646D01*
X749011Y1845729D01*
X749328Y1845646D01*
X749708Y1845396D01*
G01X752971Y1844646D02*
X754998D01*
X754808Y1845229D01*
X754491Y1845563D01*
X754048Y1845729D01*
X753604Y1845646D01*
X753224Y1845396D01*
X752971Y1844813D01*
X752844Y1844313D01*
Y1843813D01*
X752971Y1843313D01*
X753288Y1842813D01*
X753668Y1842479D01*
X754111Y1842396D01*
X754554Y1842563D01*
X754998Y1843063D01*
G01X760161Y1842396D02*
Y1845729D01*
G01Y1845146D02*
X759908Y1845479D01*
X759528Y1845646D01*
X759084Y1845729D01*
X758641Y1845563D01*
X758261Y1845229D01*
X758008Y1844729D01*
X757881Y1844063D01*
X758008Y1843396D01*
X758261Y1842896D01*
X758641Y1842563D01*
X759084Y1842396D01*
X759528Y1842479D01*
X759908Y1842729D01*
X760161Y1843063D01*
G01X763044Y1842396D02*
Y1847396D01*
G01X765071Y1845729D02*
X763044Y1843813D01*
G01X763868Y1844563D02*
X765198Y1842396D01*
G01X769221Y1847396D02*
Y1842396D01*
G01X768334Y1845729D02*
X770108D01*
G01X775461Y1842396D02*
Y1845729D01*
G01Y1845146D02*
X775208Y1845479D01*
X774828Y1845646D01*
X774384Y1845729D01*
X773941Y1845563D01*
X773561Y1845229D01*
X773308Y1844729D01*
X773181Y1844063D01*
X773308Y1843396D01*
X773561Y1842896D01*
X773941Y1842563D01*
X774384Y1842396D01*
X774828Y1842479D01*
X775208Y1842729D01*
X775461Y1843063D01*
G01X778281Y1842396D02*
Y1847396D01*
G01Y1844896D02*
X778598Y1845396D01*
X778978Y1845646D01*
X779358Y1845729D01*
X779928Y1845563D01*
X780308Y1845229D01*
X780561Y1844646D01*
Y1843979D01*
X780434Y1843313D01*
X780181Y1842813D01*
X779738Y1842479D01*
X779358Y1842396D01*
X778978Y1842479D01*
X778598Y1842729D01*
X778281Y1843146D01*
G01X784521Y1842229D02*
X784394Y1842313D01*
Y1842479D01*
X784521Y1842563D01*
X784648Y1842479D01*
Y1842313D01*
X784521Y1842229D01*
G01Y1844479D02*
X784394Y1844563D01*
Y1844729D01*
X784521Y1844813D01*
X784648Y1844729D01*
Y1844563D01*
X784521Y1844479D01*
G01X819018Y1908926D02*
Y1913926D01*
X821424D01*
G01X820538Y1911509D02*
X819018D01*
G01X825321Y1908926D02*
X824941Y1909009D01*
X824561Y1909343D01*
X824308Y1909926D01*
X824181Y1910593D01*
X824308Y1911259D01*
X824561Y1911843D01*
X824941Y1912176D01*
X825321Y1912259D01*
X825701Y1912176D01*
X826081Y1911843D01*
X826334Y1911259D01*
X826398Y1910593D01*
X826334Y1909926D01*
X826081Y1909343D01*
X825701Y1909009D01*
X825321Y1908926D01*
G01X829534D02*
Y1912259D01*
G01Y1911593D02*
X829851Y1911926D01*
X830168Y1912176D01*
X830611Y1912259D01*
X830928Y1912176D01*
X831308Y1911926D01*
G01X839354Y1908926D02*
Y1913926D01*
X840874D01*
X841381Y1913676D01*
X841761Y1913093D01*
X841888Y1912426D01*
X841761Y1911759D01*
X841444Y1911259D01*
X840874Y1911009D01*
X839354D01*
G01X846861Y1908926D02*
Y1912259D01*
G01Y1911676D02*
X846608Y1912009D01*
X846228Y1912176D01*
X845784Y1912259D01*
X845341Y1912093D01*
X844961Y1911759D01*
X844708Y1911259D01*
X844581Y1910593D01*
X844708Y1909926D01*
X844961Y1909426D01*
X845341Y1909093D01*
X845784Y1908926D01*
X846228Y1909009D01*
X846608Y1909259D01*
X846861Y1909593D01*
G01X849744Y1908926D02*
Y1912259D01*
G01Y1911426D02*
X849998Y1911843D01*
X850378Y1912176D01*
X850884Y1912259D01*
X851328Y1912176D01*
X851708Y1911843D01*
X851898Y1911259D01*
Y1908926D01*
G01X854971Y1911176D02*
X856998D01*
X856808Y1911759D01*
X856491Y1912093D01*
X856048Y1912259D01*
X855604Y1912176D01*
X855224Y1911926D01*
X854971Y1911343D01*
X854844Y1910843D01*
Y1910343D01*
X854971Y1909843D01*
X855288Y1909343D01*
X855668Y1909009D01*
X856111Y1908926D01*
X856554Y1909093D01*
X856998Y1909593D01*
G01X861021Y1908926D02*
Y1913926D01*
G01X871728Y1911593D02*
X871981Y1911843D01*
X872171Y1912259D01*
X872298Y1912843D01*
X872171Y1913343D01*
X871918Y1913676D01*
X871474Y1913926D01*
X869764D01*
Y1908926D01*
X871854D01*
X872298Y1909259D01*
X872551Y1909759D01*
X872678Y1910343D01*
X872551Y1910926D01*
X872171Y1911426D01*
X871728Y1911593D01*
X869764D01*
G01X876321Y1908926D02*
X875941Y1909009D01*
X875561Y1909343D01*
X875308Y1909926D01*
X875181Y1910593D01*
X875308Y1911259D01*
X875561Y1911843D01*
X875941Y1912176D01*
X876321Y1912259D01*
X876701Y1912176D01*
X877081Y1911843D01*
X877334Y1911259D01*
X877398Y1910593D01*
X877334Y1909926D01*
X877081Y1909343D01*
X876701Y1909009D01*
X876321Y1908926D01*
G01X882561D02*
Y1912259D01*
G01Y1911676D02*
X882308Y1912009D01*
X881928Y1912176D01*
X881484Y1912259D01*
X881041Y1912093D01*
X880661Y1911759D01*
X880408Y1911259D01*
X880281Y1910593D01*
X880408Y1909926D01*
X880661Y1909426D01*
X881041Y1909093D01*
X881484Y1908926D01*
X881928Y1909009D01*
X882308Y1909259D01*
X882561Y1909593D01*
G01X885634Y1908926D02*
Y1912259D01*
G01Y1911593D02*
X885951Y1911926D01*
X886268Y1912176D01*
X886711Y1912259D01*
X887028Y1912176D01*
X887408Y1911926D01*
G01X892761Y1913926D02*
Y1908926D01*
G01Y1909676D02*
X892508Y1909259D01*
X892128Y1909009D01*
X891684Y1908926D01*
X891178Y1909093D01*
X890798Y1909509D01*
X890544Y1910009D01*
X890481Y1910593D01*
X890544Y1911176D01*
X890798Y1911676D01*
X891178Y1912093D01*
X891684Y1912259D01*
X892128Y1912176D01*
X892444Y1912009D01*
X892761Y1911676D01*
G01X819018Y1908926D02*
Y1913926D01*
X821424D01*
G01X820538Y1911509D02*
X819018D01*
G01X825321Y1908926D02*
X824941Y1909009D01*
X824561Y1909343D01*
X824308Y1909926D01*
X824181Y1910593D01*
X824308Y1911259D01*
X824561Y1911843D01*
X824941Y1912176D01*
X825321Y1912259D01*
X825701Y1912176D01*
X826081Y1911843D01*
X826334Y1911259D01*
X826398Y1910593D01*
X826334Y1909926D01*
X826081Y1909343D01*
X825701Y1909009D01*
X825321Y1908926D01*
G01X829534D02*
Y1912259D01*
G01Y1911593D02*
X829851Y1911926D01*
X830168Y1912176D01*
X830611Y1912259D01*
X830928Y1912176D01*
X831308Y1911926D01*
G01X839354Y1908926D02*
Y1913926D01*
X840874D01*
X841381Y1913676D01*
X841761Y1913093D01*
X841888Y1912426D01*
X841761Y1911759D01*
X841444Y1911259D01*
X840874Y1911009D01*
X839354D01*
G01X846861Y1908926D02*
Y1912259D01*
G01Y1911676D02*
X846608Y1912009D01*
X846228Y1912176D01*
X845784Y1912259D01*
X845341Y1912093D01*
X844961Y1911759D01*
X844708Y1911259D01*
X844581Y1910593D01*
X844708Y1909926D01*
X844961Y1909426D01*
X845341Y1909093D01*
X845784Y1908926D01*
X846228Y1909009D01*
X846608Y1909259D01*
X846861Y1909593D01*
G01X849744Y1908926D02*
Y1912259D01*
G01Y1911426D02*
X849998Y1911843D01*
X850378Y1912176D01*
X850884Y1912259D01*
X851328Y1912176D01*
X851708Y1911843D01*
X851898Y1911259D01*
Y1908926D01*
G01X854971Y1911176D02*
X856998D01*
X856808Y1911759D01*
X856491Y1912093D01*
X856048Y1912259D01*
X855604Y1912176D01*
X855224Y1911926D01*
X854971Y1911343D01*
X854844Y1910843D01*
Y1910343D01*
X854971Y1909843D01*
X855288Y1909343D01*
X855668Y1909009D01*
X856111Y1908926D01*
X856554Y1909093D01*
X856998Y1909593D01*
G01X861021Y1908926D02*
Y1913926D01*
G01X871728Y1911593D02*
X871981Y1911843D01*
X872171Y1912259D01*
X872298Y1912843D01*
X872171Y1913343D01*
X871918Y1913676D01*
X871474Y1913926D01*
X869764D01*
Y1908926D01*
X871854D01*
X872298Y1909259D01*
X872551Y1909759D01*
X872678Y1910343D01*
X872551Y1910926D01*
X872171Y1911426D01*
X871728Y1911593D01*
X869764D01*
G01X876321Y1908926D02*
X875941Y1909009D01*
X875561Y1909343D01*
X875308Y1909926D01*
X875181Y1910593D01*
X875308Y1911259D01*
X875561Y1911843D01*
X875941Y1912176D01*
X876321Y1912259D01*
X876701Y1912176D01*
X877081Y1911843D01*
X877334Y1911259D01*
X877398Y1910593D01*
X877334Y1909926D01*
X877081Y1909343D01*
X876701Y1909009D01*
X876321Y1908926D01*
G01X882561D02*
Y1912259D01*
G01Y1911676D02*
X882308Y1912009D01*
X881928Y1912176D01*
X881484Y1912259D01*
X881041Y1912093D01*
X880661Y1911759D01*
X880408Y1911259D01*
X880281Y1910593D01*
X880408Y1909926D01*
X880661Y1909426D01*
X881041Y1909093D01*
X881484Y1908926D01*
X881928Y1909009D01*
X882308Y1909259D01*
X882561Y1909593D01*
G01X885634Y1908926D02*
Y1912259D01*
G01Y1911593D02*
X885951Y1911926D01*
X886268Y1912176D01*
X886711Y1912259D01*
X887028Y1912176D01*
X887408Y1911926D01*
G01X892761Y1913926D02*
Y1908926D01*
G01Y1909676D02*
X892508Y1909259D01*
X892128Y1909009D01*
X891684Y1908926D01*
X891178Y1909093D01*
X890798Y1909509D01*
X890544Y1910009D01*
X890481Y1910593D01*
X890544Y1911176D01*
X890798Y1911676D01*
X891178Y1912093D01*
X891684Y1912259D01*
X892128Y1912176D01*
X892444Y1912009D01*
X892761Y1911676D01*
G01X818828Y1934126D02*
Y1939126D01*
X820094D01*
X820601Y1938876D01*
X820981Y1938543D01*
X821298Y1938043D01*
X821551Y1937459D01*
X821614Y1936626D01*
X821551Y1935793D01*
X821298Y1935209D01*
X820981Y1934709D01*
X820601Y1934376D01*
X820094Y1934126D01*
X818828D01*
G01X825321Y1937459D02*
Y1934126D01*
G01Y1938793D02*
X825194Y1938876D01*
Y1939043D01*
X825321Y1939126D01*
X825448Y1939043D01*
Y1938876D01*
X825321Y1938793D01*
G01X831561Y1934126D02*
Y1937459D01*
G01Y1936876D02*
X831308Y1937209D01*
X830928Y1937376D01*
X830484Y1937459D01*
X830041Y1937293D01*
X829661Y1936959D01*
X829408Y1936459D01*
X829281Y1935793D01*
X829408Y1935126D01*
X829661Y1934626D01*
X830041Y1934293D01*
X830484Y1934126D01*
X830928Y1934209D01*
X831308Y1934459D01*
X831561Y1934793D01*
G01X833621Y1934126D02*
Y1937459D01*
G01Y1936543D02*
X833811Y1936959D01*
X834128Y1937293D01*
X834571Y1937459D01*
X835014Y1937293D01*
X835331Y1936959D01*
X835521Y1936543D01*
Y1934126D01*
G01Y1936543D02*
X835711Y1936959D01*
X836028Y1937293D01*
X836471Y1937459D01*
X836914Y1937293D01*
X837231Y1936959D01*
X837421Y1936459D01*
Y1934126D01*
G01X839671Y1936376D02*
X841698D01*
X841508Y1936959D01*
X841191Y1937293D01*
X840748Y1937459D01*
X840304Y1937376D01*
X839924Y1937126D01*
X839671Y1936543D01*
X839544Y1936043D01*
Y1935543D01*
X839671Y1935043D01*
X839988Y1934543D01*
X840368Y1934209D01*
X840811Y1934126D01*
X841254Y1934293D01*
X841698Y1934793D01*
G01X845721Y1939126D02*
Y1934126D01*
G01X844834Y1937459D02*
X846608D01*
G01X849871Y1936376D02*
X851898D01*
X851708Y1936959D01*
X851391Y1937293D01*
X850948Y1937459D01*
X850504Y1937376D01*
X850124Y1937126D01*
X849871Y1936543D01*
X849744Y1936043D01*
Y1935543D01*
X849871Y1935043D01*
X850188Y1934543D01*
X850568Y1934209D01*
X851011Y1934126D01*
X851454Y1934293D01*
X851898Y1934793D01*
G01X855034Y1934126D02*
Y1937459D01*
G01Y1936793D02*
X855351Y1937126D01*
X855668Y1937376D01*
X856111Y1937459D01*
X856428Y1937376D01*
X856808Y1937126D01*
G01X864728Y1935126D02*
X865108Y1934543D01*
X865614Y1934209D01*
X866184Y1934126D01*
X866691Y1934209D01*
X867198Y1934626D01*
X867514Y1935126D01*
X867578Y1935626D01*
X867451Y1936209D01*
X867008Y1936626D01*
X866564Y1936793D01*
X865994D01*
G01X866564D02*
X866944Y1937043D01*
X867261Y1937459D01*
X867388Y1937959D01*
X867261Y1938459D01*
X866944Y1938876D01*
X866374Y1939126D01*
X865804Y1939043D01*
X865234Y1938709D01*
G01X869321Y1934126D02*
Y1937459D01*
G01Y1936543D02*
X869511Y1936959D01*
X869828Y1937293D01*
X870271Y1937459D01*
X870714Y1937293D01*
X871031Y1936959D01*
X871221Y1936543D01*
Y1934126D01*
G01Y1936543D02*
X871411Y1936959D01*
X871728Y1937293D01*
X872171Y1937459D01*
X872614Y1937293D01*
X872931Y1936959D01*
X873121Y1936459D01*
Y1934126D01*
G01X874421D02*
Y1937459D01*
G01Y1936543D02*
X874611Y1936959D01*
X874928Y1937293D01*
X875371Y1937459D01*
X875814Y1937293D01*
X876131Y1936959D01*
X876321Y1936543D01*
Y1934126D01*
G01Y1936543D02*
X876511Y1936959D01*
X876828Y1937293D01*
X877271Y1937459D01*
X877714Y1937293D01*
X878031Y1936959D01*
X878221Y1936459D01*
Y1934126D01*
G01X885191Y1934793D02*
X885698Y1934376D01*
X886268Y1934126D01*
X886774D01*
X887281Y1934376D01*
X887661Y1934793D01*
X887851Y1935376D01*
X887724Y1935959D01*
X887408Y1936459D01*
X886838Y1936793D01*
X886078Y1936959D01*
X885634Y1937293D01*
X885444Y1937876D01*
X885571Y1938459D01*
X885888Y1938876D01*
X886331Y1939126D01*
X886774D01*
X887218Y1938959D01*
X887598Y1938543D01*
G01X891621Y1934126D02*
X891241Y1934209D01*
X890861Y1934543D01*
X890608Y1935126D01*
X890481Y1935793D01*
X890608Y1936459D01*
X890861Y1937043D01*
X891241Y1937376D01*
X891621Y1937459D01*
X892001Y1937376D01*
X892381Y1937043D01*
X892634Y1936459D01*
X892698Y1935793D01*
X892634Y1935126D01*
X892381Y1934543D01*
X892001Y1934209D01*
X891621Y1934126D01*
G01X896721D02*
Y1939126D01*
G01X902961D02*
Y1934126D01*
G01Y1934876D02*
X902708Y1934459D01*
X902328Y1934209D01*
X901884Y1934126D01*
X901378Y1934293D01*
X900998Y1934709D01*
X900744Y1935209D01*
X900681Y1935793D01*
X900744Y1936376D01*
X900998Y1936876D01*
X901378Y1937293D01*
X901884Y1937459D01*
X902328Y1937376D01*
X902644Y1937209D01*
X902961Y1936876D01*
G01X905971Y1936376D02*
X907998D01*
X907808Y1936959D01*
X907491Y1937293D01*
X907048Y1937459D01*
X906604Y1937376D01*
X906224Y1937126D01*
X905971Y1936543D01*
X905844Y1936043D01*
Y1935543D01*
X905971Y1935043D01*
X906288Y1934543D01*
X906668Y1934209D01*
X907111Y1934126D01*
X907554Y1934293D01*
X907998Y1934793D01*
G01X911134Y1934126D02*
Y1937459D01*
G01Y1936793D02*
X911451Y1937126D01*
X911768Y1937376D01*
X912211Y1937459D01*
X912528Y1937376D01*
X912908Y1937126D01*
G01X915221Y1934126D02*
Y1937459D01*
G01Y1936543D02*
X915411Y1936959D01*
X915728Y1937293D01*
X916171Y1937459D01*
X916614Y1937293D01*
X916931Y1936959D01*
X917121Y1936543D01*
Y1934126D01*
G01Y1936543D02*
X917311Y1936959D01*
X917628Y1937293D01*
X918071Y1937459D01*
X918514Y1937293D01*
X918831Y1936959D01*
X919021Y1936459D01*
Y1934126D01*
G01X923361D02*
Y1937459D01*
G01Y1936876D02*
X923108Y1937209D01*
X922728Y1937376D01*
X922284Y1937459D01*
X921841Y1937293D01*
X921461Y1936959D01*
X921208Y1936459D01*
X921081Y1935793D01*
X921208Y1935126D01*
X921461Y1934626D01*
X921841Y1934293D01*
X922284Y1934126D01*
X922728Y1934209D01*
X923108Y1934459D01*
X923361Y1934793D01*
G01X926371Y1934709D02*
X926688Y1934376D01*
X927131Y1934126D01*
X927511D01*
X927891Y1934293D01*
X928144Y1934543D01*
X928271Y1934876D01*
X928208Y1935376D01*
X927954Y1935626D01*
X926814Y1936126D01*
X926561Y1936709D01*
X926688Y1937126D01*
X926941Y1937376D01*
X927321Y1937459D01*
X927701Y1937376D01*
X928081Y1937126D01*
G01X931344Y1934126D02*
Y1939126D01*
G01X933371Y1937459D02*
X931344Y1935543D01*
G01X932168Y1936293D02*
X933498Y1934126D01*
G01X820221Y1926526D02*
Y1921526D01*
G01X818764Y1926526D02*
X821678D01*
G01X825321Y1921526D02*
X824941Y1921609D01*
X824561Y1921943D01*
X824308Y1922526D01*
X824181Y1923193D01*
X824308Y1923859D01*
X824561Y1924443D01*
X824941Y1924776D01*
X825321Y1924859D01*
X825701Y1924776D01*
X826081Y1924443D01*
X826334Y1923859D01*
X826398Y1923193D01*
X826334Y1922526D01*
X826081Y1921943D01*
X825701Y1921609D01*
X825321Y1921526D01*
G01X829281Y1919859D02*
Y1924859D01*
G01Y1924109D02*
X829598Y1924526D01*
X829914Y1924776D01*
X830421Y1924859D01*
X830864Y1924776D01*
X831308Y1924359D01*
X831498Y1923776D01*
X831561Y1923193D01*
X831498Y1922609D01*
X831308Y1922026D01*
X830928Y1921693D01*
X830421Y1921526D01*
X829978Y1921609D01*
X829534Y1921859D01*
X829281Y1922193D01*
G01X839038Y1921526D02*
X840621Y1926526D01*
X842204Y1921526D01*
G01X841634Y1923276D02*
X839608D01*
G01X844644Y1921526D02*
Y1924859D01*
G01Y1924026D02*
X844898Y1924443D01*
X845278Y1924776D01*
X845784Y1924859D01*
X846228Y1924776D01*
X846608Y1924443D01*
X846798Y1923859D01*
Y1921526D01*
G01X851961Y1926526D02*
Y1921526D01*
G01Y1922276D02*
X851708Y1921859D01*
X851328Y1921609D01*
X850884Y1921526D01*
X850378Y1921693D01*
X849998Y1922109D01*
X849744Y1922609D01*
X849681Y1923193D01*
X849744Y1923776D01*
X849998Y1924276D01*
X850378Y1924693D01*
X850884Y1924859D01*
X851328Y1924776D01*
X851644Y1924609D01*
X851961Y1924276D01*
G01X861528Y1924193D02*
X861781Y1924443D01*
X861971Y1924859D01*
X862098Y1925443D01*
X861971Y1925943D01*
X861718Y1926276D01*
X861274Y1926526D01*
X859564D01*
Y1921526D01*
X861654D01*
X862098Y1921859D01*
X862351Y1922359D01*
X862478Y1922943D01*
X862351Y1923526D01*
X861971Y1924026D01*
X861528Y1924193D01*
X859564D01*
G01X866121Y1921526D02*
X865741Y1921609D01*
X865361Y1921943D01*
X865108Y1922526D01*
X864981Y1923193D01*
X865108Y1923859D01*
X865361Y1924443D01*
X865741Y1924776D01*
X866121Y1924859D01*
X866501Y1924776D01*
X866881Y1924443D01*
X867134Y1923859D01*
X867198Y1923193D01*
X867134Y1922526D01*
X866881Y1921943D01*
X866501Y1921609D01*
X866121Y1921526D01*
G01X871221Y1926526D02*
Y1921526D01*
G01X870334Y1924859D02*
X872108D01*
G01X876321Y1926526D02*
Y1921526D01*
G01X875434Y1924859D02*
X877208D01*
G01X881421Y1921526D02*
X881041Y1921609D01*
X880661Y1921943D01*
X880408Y1922526D01*
X880281Y1923193D01*
X880408Y1923859D01*
X880661Y1924443D01*
X881041Y1924776D01*
X881421Y1924859D01*
X881801Y1924776D01*
X882181Y1924443D01*
X882434Y1923859D01*
X882498Y1923193D01*
X882434Y1922526D01*
X882181Y1921943D01*
X881801Y1921609D01*
X881421Y1921526D01*
G01X884621D02*
Y1924859D01*
G01Y1923943D02*
X884811Y1924359D01*
X885128Y1924693D01*
X885571Y1924859D01*
X886014Y1924693D01*
X886331Y1924359D01*
X886521Y1923943D01*
Y1921526D01*
G01Y1923943D02*
X886711Y1924359D01*
X887028Y1924693D01*
X887471Y1924859D01*
X887914Y1924693D01*
X888231Y1924359D01*
X888421Y1923859D01*
Y1921526D01*
G01X895391Y1922193D02*
X895898Y1921776D01*
X896468Y1921526D01*
X896974D01*
X897481Y1921776D01*
X897861Y1922193D01*
X898051Y1922776D01*
X897924Y1923359D01*
X897608Y1923859D01*
X897038Y1924193D01*
X896278Y1924359D01*
X895834Y1924693D01*
X895644Y1925276D01*
X895771Y1925859D01*
X896088Y1926276D01*
X896531Y1926526D01*
X896974D01*
X897418Y1926359D01*
X897798Y1925943D01*
G01X901821Y1924859D02*
Y1921526D01*
G01Y1926193D02*
X901694Y1926276D01*
Y1926443D01*
X901821Y1926526D01*
X901948Y1926443D01*
Y1926276D01*
X901821Y1926193D01*
G01X908061Y1926526D02*
Y1921526D01*
G01Y1922276D02*
X907808Y1921859D01*
X907428Y1921609D01*
X906984Y1921526D01*
X906478Y1921693D01*
X906098Y1922109D01*
X905844Y1922609D01*
X905781Y1923193D01*
X905844Y1923776D01*
X906098Y1924276D01*
X906478Y1924693D01*
X906984Y1924859D01*
X907428Y1924776D01*
X907744Y1924609D01*
X908061Y1924276D01*
G01X911071Y1923776D02*
X913098D01*
X912908Y1924359D01*
X912591Y1924693D01*
X912148Y1924859D01*
X911704Y1924776D01*
X911324Y1924526D01*
X911071Y1923943D01*
X910944Y1923443D01*
Y1922943D01*
X911071Y1922443D01*
X911388Y1921943D01*
X911768Y1921609D01*
X912211Y1921526D01*
X912654Y1921693D01*
X913098Y1922193D01*
G01X742518Y1946726D02*
Y1951726D01*
X744924D01*
G01X744038Y1949309D02*
X742518D01*
G01X748821Y1950059D02*
Y1946726D01*
G01Y1951393D02*
X748694Y1951476D01*
Y1951643D01*
X748821Y1951726D01*
X748948Y1951643D01*
Y1951476D01*
X748821Y1951393D01*
G01X755061Y1951726D02*
Y1946726D01*
G01Y1947476D02*
X754808Y1947059D01*
X754428Y1946809D01*
X753984Y1946726D01*
X753478Y1946893D01*
X753098Y1947309D01*
X752844Y1947809D01*
X752781Y1948393D01*
X752844Y1948976D01*
X753098Y1949476D01*
X753478Y1949893D01*
X753984Y1950059D01*
X754428Y1949976D01*
X754744Y1949809D01*
X755061Y1949476D01*
G01X757944Y1950059D02*
Y1947726D01*
X758198Y1947143D01*
X758578Y1946809D01*
X759021Y1946726D01*
X759464Y1946809D01*
X759844Y1947143D01*
X760098Y1947726D01*
G01Y1946726D02*
Y1950059D01*
G01X765134Y1949643D02*
X764691Y1949976D01*
X764311Y1950059D01*
X763804Y1949893D01*
X763424Y1949559D01*
X763171Y1948976D01*
X763108Y1948393D01*
X763171Y1947809D01*
X763424Y1947309D01*
X763804Y1946893D01*
X764311Y1946726D01*
X764754Y1946893D01*
X765134Y1947226D01*
G01X769221Y1950059D02*
Y1946726D01*
G01Y1951393D02*
X769094Y1951476D01*
Y1951643D01*
X769221Y1951726D01*
X769348Y1951643D01*
Y1951476D01*
X769221Y1951393D01*
G01X775461Y1946726D02*
Y1950059D01*
G01Y1949476D02*
X775208Y1949809D01*
X774828Y1949976D01*
X774384Y1950059D01*
X773941Y1949893D01*
X773561Y1949559D01*
X773308Y1949059D01*
X773181Y1948393D01*
X773308Y1947726D01*
X773561Y1947226D01*
X773941Y1946893D01*
X774384Y1946726D01*
X774828Y1946809D01*
X775208Y1947059D01*
X775461Y1947393D01*
G01X779421Y1946726D02*
Y1951726D01*
G01X787974Y1946726D02*
Y1951726D01*
X789621Y1947559D01*
X791268Y1951726D01*
Y1946726D01*
G01X795861D02*
Y1950059D01*
G01Y1949476D02*
X795608Y1949809D01*
X795228Y1949976D01*
X794784Y1950059D01*
X794341Y1949893D01*
X793961Y1949559D01*
X793708Y1949059D01*
X793581Y1948393D01*
X793708Y1947726D01*
X793961Y1947226D01*
X794341Y1946893D01*
X794784Y1946726D01*
X795228Y1946809D01*
X795608Y1947059D01*
X795861Y1947393D01*
G01X798934Y1946726D02*
Y1950059D01*
G01Y1949393D02*
X799251Y1949726D01*
X799568Y1949976D01*
X800011Y1950059D01*
X800328Y1949976D01*
X800708Y1949726D01*
G01X803844Y1946726D02*
Y1951726D01*
G01X805871Y1950059D02*
X803844Y1948143D01*
G01X804668Y1948893D02*
X805998Y1946726D01*
G01X810021Y1946559D02*
X809894Y1946643D01*
Y1946809D01*
X810021Y1946893D01*
X810148Y1946809D01*
Y1946643D01*
X810021Y1946559D01*
G01Y1948809D02*
X809894Y1948893D01*
Y1949059D01*
X810021Y1949143D01*
X810148Y1949059D01*
Y1948893D01*
X810021Y1948809D01*
G01X818828Y1946726D02*
Y1951726D01*
X820094D01*
X820601Y1951476D01*
X820981Y1951143D01*
X821298Y1950643D01*
X821551Y1950059D01*
X821614Y1949226D01*
X821551Y1948393D01*
X821298Y1947809D01*
X820981Y1947309D01*
X820601Y1946976D01*
X820094Y1946726D01*
X818828D01*
G01X825321Y1950059D02*
Y1946726D01*
G01Y1951393D02*
X825194Y1951476D01*
Y1951643D01*
X825321Y1951726D01*
X825448Y1951643D01*
Y1951476D01*
X825321Y1951393D01*
G01X831561Y1946726D02*
Y1950059D01*
G01Y1949476D02*
X831308Y1949809D01*
X830928Y1949976D01*
X830484Y1950059D01*
X830041Y1949893D01*
X829661Y1949559D01*
X829408Y1949059D01*
X829281Y1948393D01*
X829408Y1947726D01*
X829661Y1947226D01*
X830041Y1946893D01*
X830484Y1946726D01*
X830928Y1946809D01*
X831308Y1947059D01*
X831561Y1947393D01*
G01X833621Y1946726D02*
Y1950059D01*
G01Y1949143D02*
X833811Y1949559D01*
X834128Y1949893D01*
X834571Y1950059D01*
X835014Y1949893D01*
X835331Y1949559D01*
X835521Y1949143D01*
Y1946726D01*
G01Y1949143D02*
X835711Y1949559D01*
X836028Y1949893D01*
X836471Y1950059D01*
X836914Y1949893D01*
X837231Y1949559D01*
X837421Y1949059D01*
Y1946726D01*
G01X839671Y1948976D02*
X841698D01*
X841508Y1949559D01*
X841191Y1949893D01*
X840748Y1950059D01*
X840304Y1949976D01*
X839924Y1949726D01*
X839671Y1949143D01*
X839544Y1948643D01*
Y1948143D01*
X839671Y1947643D01*
X839988Y1947143D01*
X840368Y1946809D01*
X840811Y1946726D01*
X841254Y1946893D01*
X841698Y1947393D01*
G01X845721Y1951726D02*
Y1946726D01*
G01X844834Y1950059D02*
X846608D01*
G01X849871Y1948976D02*
X851898D01*
X851708Y1949559D01*
X851391Y1949893D01*
X850948Y1950059D01*
X850504Y1949976D01*
X850124Y1949726D01*
X849871Y1949143D01*
X849744Y1948643D01*
Y1948143D01*
X849871Y1947643D01*
X850188Y1947143D01*
X850568Y1946809D01*
X851011Y1946726D01*
X851454Y1946893D01*
X851898Y1947393D01*
G01X855034Y1946726D02*
Y1950059D01*
G01Y1949393D02*
X855351Y1949726D01*
X855668Y1949976D01*
X856111Y1950059D01*
X856428Y1949976D01*
X856808Y1949726D01*
G01X866121Y1946726D02*
Y1951726D01*
X865361Y1950726D01*
G01Y1946726D02*
X866881D01*
G01X869321D02*
Y1950059D01*
G01Y1949143D02*
X869511Y1949559D01*
X869828Y1949893D01*
X870271Y1950059D01*
X870714Y1949893D01*
X871031Y1949559D01*
X871221Y1949143D01*
Y1946726D01*
G01Y1949143D02*
X871411Y1949559D01*
X871728Y1949893D01*
X872171Y1950059D01*
X872614Y1949893D01*
X872931Y1949559D01*
X873121Y1949059D01*
Y1946726D01*
G01X874421D02*
Y1950059D01*
G01Y1949143D02*
X874611Y1949559D01*
X874928Y1949893D01*
X875371Y1950059D01*
X875814Y1949893D01*
X876131Y1949559D01*
X876321Y1949143D01*
Y1946726D01*
G01Y1949143D02*
X876511Y1949559D01*
X876828Y1949893D01*
X877271Y1950059D01*
X877714Y1949893D01*
X878031Y1949559D01*
X878221Y1949059D01*
Y1946726D01*
G01X887914Y1951309D02*
X887534Y1951559D01*
X887091Y1951726D01*
X886584D01*
X886014Y1951476D01*
X885571Y1951059D01*
X885254Y1950559D01*
X885001Y1949726D01*
X884938Y1948976D01*
X885064Y1948226D01*
X885254Y1947726D01*
X885634Y1947226D01*
X886078Y1946893D01*
X886521Y1946726D01*
X886964D01*
X887408Y1946893D01*
X887788Y1947143D01*
X888104Y1947476D01*
G01X891621Y1946726D02*
X891241Y1946809D01*
X890861Y1947143D01*
X890608Y1947726D01*
X890481Y1948393D01*
X890608Y1949059D01*
X890861Y1949643D01*
X891241Y1949976D01*
X891621Y1950059D01*
X892001Y1949976D01*
X892381Y1949643D01*
X892634Y1949059D01*
X892698Y1948393D01*
X892634Y1947726D01*
X892381Y1947143D01*
X892001Y1946809D01*
X891621Y1946726D01*
G01X895581Y1945059D02*
Y1950059D01*
G01Y1949309D02*
X895898Y1949726D01*
X896214Y1949976D01*
X896721Y1950059D01*
X897164Y1949976D01*
X897608Y1949559D01*
X897798Y1948976D01*
X897861Y1948393D01*
X897798Y1947809D01*
X897608Y1947226D01*
X897228Y1946893D01*
X896721Y1946726D01*
X896278Y1946809D01*
X895834Y1947059D01*
X895581Y1947393D01*
G01X900681Y1945059D02*
Y1950059D01*
G01Y1949309D02*
X900998Y1949726D01*
X901314Y1949976D01*
X901821Y1950059D01*
X902264Y1949976D01*
X902708Y1949559D01*
X902898Y1948976D01*
X902961Y1948393D01*
X902898Y1947809D01*
X902708Y1947226D01*
X902328Y1946893D01*
X901821Y1946726D01*
X901378Y1946809D01*
X900934Y1947059D01*
X900681Y1947393D01*
G01X905971Y1948976D02*
X907998D01*
X907808Y1949559D01*
X907491Y1949893D01*
X907048Y1950059D01*
X906604Y1949976D01*
X906224Y1949726D01*
X905971Y1949143D01*
X905844Y1948643D01*
Y1948143D01*
X905971Y1947643D01*
X906288Y1947143D01*
X906668Y1946809D01*
X907111Y1946726D01*
X907554Y1946893D01*
X907998Y1947393D01*
G01X911134Y1946726D02*
Y1950059D01*
G01Y1949393D02*
X911451Y1949726D01*
X911768Y1949976D01*
X912211Y1950059D01*
X912528Y1949976D01*
X912908Y1949726D01*
G01X815909Y2008418D02*
Y2003418D01*
G01X814452Y2008418D02*
X817366D01*
G01X821009Y2003418D02*
X820629Y2003501D01*
X820249Y2003835D01*
X819996Y2004418D01*
X819869Y2005085D01*
X819996Y2005751D01*
X820249Y2006335D01*
X820629Y2006668D01*
X821009Y2006751D01*
X821389Y2006668D01*
X821769Y2006335D01*
X822022Y2005751D01*
X822086Y2005085D01*
X822022Y2004418D01*
X821769Y2003835D01*
X821389Y2003501D01*
X821009Y2003418D01*
G01X826109D02*
Y2008418D01*
G01X830259Y2005668D02*
X832286D01*
X832096Y2006251D01*
X831779Y2006585D01*
X831336Y2006751D01*
X830892Y2006668D01*
X830512Y2006418D01*
X830259Y2005835D01*
X830132Y2005335D01*
Y2004835D01*
X830259Y2004335D01*
X830576Y2003835D01*
X830956Y2003501D01*
X831399Y2003418D01*
X831842Y2003585D01*
X832286Y2004085D01*
G01X835422Y2003418D02*
Y2006751D01*
G01Y2006085D02*
X835739Y2006418D01*
X836056Y2006668D01*
X836499Y2006751D01*
X836816Y2006668D01*
X837196Y2006418D01*
G01X842549Y2003418D02*
Y2006751D01*
G01Y2006168D02*
X842296Y2006501D01*
X841916Y2006668D01*
X841472Y2006751D01*
X841029Y2006585D01*
X840649Y2006251D01*
X840396Y2005751D01*
X840269Y2005085D01*
X840396Y2004418D01*
X840649Y2003918D01*
X841029Y2003585D01*
X841472Y2003418D01*
X841916Y2003501D01*
X842296Y2003751D01*
X842549Y2004085D01*
G01X845432Y2003418D02*
Y2006751D01*
G01Y2005918D02*
X845686Y2006335D01*
X846066Y2006668D01*
X846572Y2006751D01*
X847016Y2006668D01*
X847396Y2006335D01*
X847586Y2005751D01*
Y2003418D01*
G01X852622Y2006335D02*
X852179Y2006668D01*
X851799Y2006751D01*
X851292Y2006585D01*
X850912Y2006251D01*
X850659Y2005668D01*
X850596Y2005085D01*
X850659Y2004501D01*
X850912Y2004001D01*
X851292Y2003585D01*
X851799Y2003418D01*
X852242Y2003585D01*
X852622Y2003918D01*
G01X855759Y2005668D02*
X857786D01*
X857596Y2006251D01*
X857279Y2006585D01*
X856836Y2006751D01*
X856392Y2006668D01*
X856012Y2006418D01*
X855759Y2005835D01*
X855632Y2005335D01*
Y2004835D01*
X855759Y2004335D01*
X856076Y2003835D01*
X856456Y2003501D01*
X856899Y2003418D01*
X857342Y2003585D01*
X857786Y2004085D01*
G01X866212Y2005085D02*
X867732D01*
G01X866909Y2006168D02*
Y2004001D01*
G01X872009Y2008418D02*
X871502Y2008251D01*
X871122Y2007835D01*
X870869Y2007335D01*
X870679Y2006668D01*
X870616Y2005918D01*
X870679Y2005168D01*
X870869Y2004501D01*
X871122Y2004001D01*
X871502Y2003585D01*
X872009Y2003418D01*
X872516Y2003585D01*
X872896Y2004001D01*
X873149Y2004501D01*
X873339Y2005168D01*
X873402Y2005918D01*
X873339Y2006668D01*
X873149Y2007335D01*
X872896Y2007835D01*
X872516Y2008251D01*
X872009Y2008418D01*
G01X877109Y2003251D02*
X876982Y2003335D01*
Y2003501D01*
X877109Y2003585D01*
X877236Y2003501D01*
Y2003335D01*
X877109Y2003251D01*
G01X882209Y2008418D02*
X881702Y2008251D01*
X881322Y2007835D01*
X881069Y2007335D01*
X880879Y2006668D01*
X880816Y2005918D01*
X880879Y2005168D01*
X881069Y2004501D01*
X881322Y2004001D01*
X881702Y2003585D01*
X882209Y2003418D01*
X882716Y2003585D01*
X883096Y2004001D01*
X883349Y2004501D01*
X883539Y2005168D01*
X883602Y2005918D01*
X883539Y2006668D01*
X883349Y2007335D01*
X883096Y2007835D01*
X882716Y2008251D01*
X882209Y2008418D01*
G01X885916Y2004168D02*
X886296Y2003751D01*
X886739Y2003501D01*
X887309Y2003418D01*
X887879Y2003585D01*
X888322Y2003918D01*
X888639Y2004501D01*
X888702Y2005168D01*
X888576Y2005835D01*
X888259Y2006251D01*
X887816Y2006585D01*
X887372Y2006668D01*
X886929Y2006585D01*
X886359Y2006251D01*
X886549Y2008418D01*
X888259D01*
G01X892409D02*
X891902Y2008251D01*
X891522Y2007835D01*
X891269Y2007335D01*
X891079Y2006668D01*
X891016Y2005918D01*
X891079Y2005168D01*
X891269Y2004501D01*
X891522Y2004001D01*
X891902Y2003585D01*
X892409Y2003418D01*
X892916Y2003585D01*
X893296Y2004001D01*
X893549Y2004501D01*
X893739Y2005168D01*
X893802Y2005918D01*
X893739Y2006668D01*
X893549Y2007335D01*
X893296Y2007835D01*
X892916Y2008251D01*
X892409Y2008418D01*
G01X897509Y2003418D02*
X897952Y2003501D01*
X898459Y2003751D01*
X898776Y2004168D01*
X898902Y2004751D01*
X898776Y2005335D01*
X898396Y2005835D01*
X897826Y2006085D01*
X897192D01*
X896812Y2006251D01*
X896496Y2006668D01*
X896369Y2007251D01*
X896559Y2007835D01*
X897002Y2008251D01*
X897509Y2008418D01*
X898016Y2008251D01*
X898459Y2007835D01*
X898649Y2007251D01*
X898522Y2006668D01*
X898206Y2006251D01*
X897826Y2006085D01*
X897192D01*
X896622Y2005835D01*
X896242Y2005335D01*
X896116Y2004751D01*
X896242Y2004168D01*
X896559Y2003751D01*
X897066Y2003501D01*
X897509Y2003418D01*
G01X900709D02*
Y2006751D01*
G01Y2005835D02*
X900899Y2006251D01*
X901216Y2006585D01*
X901659Y2006751D01*
X902102Y2006585D01*
X902419Y2006251D01*
X902609Y2005835D01*
Y2003418D01*
G01Y2005835D02*
X902799Y2006251D01*
X903116Y2006585D01*
X903559Y2006751D01*
X904002Y2006585D01*
X904319Y2006251D01*
X904509Y2005751D01*
Y2003418D01*
G01X905809D02*
Y2006751D01*
G01Y2005835D02*
X905999Y2006251D01*
X906316Y2006585D01*
X906759Y2006751D01*
X907202Y2006585D01*
X907519Y2006251D01*
X907709Y2005835D01*
Y2003418D01*
G01Y2005835D02*
X907899Y2006251D01*
X908216Y2006585D01*
X908659Y2006751D01*
X909102Y2006585D01*
X909419Y2006251D01*
X909609Y2005751D01*
Y2003418D01*
G01X911669Y2003251D02*
X913949Y2008418D01*
G01X917086Y2005085D02*
X918732D01*
G01X923009Y2008418D02*
X922502Y2008251D01*
X922122Y2007835D01*
X921869Y2007335D01*
X921679Y2006668D01*
X921616Y2005918D01*
X921679Y2005168D01*
X921869Y2004501D01*
X922122Y2004001D01*
X922502Y2003585D01*
X923009Y2003418D01*
X923516Y2003585D01*
X923896Y2004001D01*
X924149Y2004501D01*
X924339Y2005168D01*
X924402Y2005918D01*
X924339Y2006668D01*
X924149Y2007335D01*
X923896Y2007835D01*
X923516Y2008251D01*
X923009Y2008418D01*
G01X928109Y2003251D02*
X927982Y2003335D01*
Y2003501D01*
X928109Y2003585D01*
X928236Y2003501D01*
Y2003335D01*
X928109Y2003251D01*
G01X933209Y2008418D02*
X932702Y2008251D01*
X932322Y2007835D01*
X932069Y2007335D01*
X931879Y2006668D01*
X931816Y2005918D01*
X931879Y2005168D01*
X932069Y2004501D01*
X932322Y2004001D01*
X932702Y2003585D01*
X933209Y2003418D01*
X933716Y2003585D01*
X934096Y2004001D01*
X934349Y2004501D01*
X934539Y2005168D01*
X934602Y2005918D01*
X934539Y2006668D01*
X934349Y2007335D01*
X934096Y2007835D01*
X933716Y2008251D01*
X933209Y2008418D01*
G01X937106Y2007585D02*
X937486Y2008085D01*
X937929Y2008335D01*
X938436Y2008418D01*
X939069Y2008251D01*
X939512Y2007835D01*
X939639Y2007335D01*
X939576Y2006835D01*
X939322Y2006418D01*
X938056Y2005585D01*
X937486Y2005001D01*
X937106Y2004168D01*
X936979Y2003418D01*
X939639D01*
G01X942016Y2004168D02*
X942396Y2003751D01*
X942839Y2003501D01*
X943409Y2003418D01*
X943979Y2003585D01*
X944422Y2003918D01*
X944739Y2004501D01*
X944802Y2005168D01*
X944676Y2005835D01*
X944359Y2006251D01*
X943916Y2006585D01*
X943472Y2006668D01*
X943029Y2006585D01*
X942459Y2006251D01*
X942649Y2008418D01*
X944359D01*
G01X949269Y2003418D02*
Y2008418D01*
X946926Y2004835D01*
X950092D01*
G01X951709Y2003418D02*
Y2006751D01*
G01Y2005835D02*
X951899Y2006251D01*
X952216Y2006585D01*
X952659Y2006751D01*
X953102Y2006585D01*
X953419Y2006251D01*
X953609Y2005835D01*
Y2003418D01*
G01Y2005835D02*
X953799Y2006251D01*
X954116Y2006585D01*
X954559Y2006751D01*
X955002Y2006585D01*
X955319Y2006251D01*
X955509Y2005751D01*
Y2003418D01*
G01X956809D02*
Y2006751D01*
G01Y2005835D02*
X956999Y2006251D01*
X957316Y2006585D01*
X957759Y2006751D01*
X958202Y2006585D01*
X958519Y2006251D01*
X958709Y2005835D01*
Y2003418D01*
G01Y2005835D02*
X958899Y2006251D01*
X959216Y2006585D01*
X959659Y2006751D01*
X960102Y2006585D01*
X960419Y2006251D01*
X960609Y2005751D01*
Y2003418D01*
G01X744509Y2021018D02*
Y2016018D01*
G01X743052Y2021018D02*
X745966D01*
G01X749609Y2016018D02*
X749229Y2016101D01*
X748849Y2016435D01*
X748596Y2017018D01*
X748469Y2017685D01*
X748596Y2018351D01*
X748849Y2018935D01*
X749229Y2019268D01*
X749609Y2019351D01*
X749989Y2019268D01*
X750369Y2018935D01*
X750622Y2018351D01*
X750686Y2017685D01*
X750622Y2017018D01*
X750369Y2016435D01*
X749989Y2016101D01*
X749609Y2016018D01*
G01X754709D02*
X754329Y2016101D01*
X753949Y2016435D01*
X753696Y2017018D01*
X753569Y2017685D01*
X753696Y2018351D01*
X753949Y2018935D01*
X754329Y2019268D01*
X754709Y2019351D01*
X755089Y2019268D01*
X755469Y2018935D01*
X755722Y2018351D01*
X755786Y2017685D01*
X755722Y2017018D01*
X755469Y2016435D01*
X755089Y2016101D01*
X754709Y2016018D01*
G01X759809D02*
Y2021018D01*
G01X764909Y2019351D02*
Y2016018D01*
G01Y2020685D02*
X764782Y2020768D01*
Y2020935D01*
X764909Y2021018D01*
X765036Y2020935D01*
Y2020768D01*
X764909Y2020685D01*
G01X768932Y2016018D02*
Y2019351D01*
G01Y2018518D02*
X769186Y2018935D01*
X769566Y2019268D01*
X770072Y2019351D01*
X770516Y2019268D01*
X770896Y2018935D01*
X771086Y2018351D01*
Y2016018D01*
G01X774222Y2014768D02*
X774666Y2014435D01*
X775172Y2014351D01*
X775616Y2014435D01*
X775996Y2014851D01*
X776249Y2015435D01*
Y2019351D01*
G01Y2018685D02*
X775996Y2019018D01*
X775616Y2019268D01*
X775172Y2019351D01*
X774666Y2019185D01*
X774349Y2018851D01*
X774096Y2018268D01*
X773969Y2017685D01*
X774032Y2017185D01*
X774286Y2016601D01*
X774666Y2016185D01*
X775172Y2016018D01*
X775552Y2016101D01*
X775996Y2016435D01*
X776249Y2016768D01*
G01X783979Y2016018D02*
Y2021018D01*
G01X786639D02*
Y2016018D01*
G01Y2018518D02*
X783979D01*
G01X790409Y2016018D02*
X790029Y2016101D01*
X789649Y2016435D01*
X789396Y2017018D01*
X789269Y2017685D01*
X789396Y2018351D01*
X789649Y2018935D01*
X790029Y2019268D01*
X790409Y2019351D01*
X790789Y2019268D01*
X791169Y2018935D01*
X791422Y2018351D01*
X791486Y2017685D01*
X791422Y2017018D01*
X791169Y2016435D01*
X790789Y2016101D01*
X790409Y2016018D01*
G01X795509D02*
Y2021018D01*
G01X799659Y2018268D02*
X801686D01*
X801496Y2018851D01*
X801179Y2019185D01*
X800736Y2019351D01*
X800292Y2019268D01*
X799912Y2019018D01*
X799659Y2018435D01*
X799532Y2017935D01*
Y2017435D01*
X799659Y2016935D01*
X799976Y2016435D01*
X800356Y2016101D01*
X800799Y2016018D01*
X801242Y2016185D01*
X801686Y2016685D01*
G01X805709Y2015851D02*
X805582Y2015935D01*
Y2016101D01*
X805709Y2016185D01*
X805836Y2016101D01*
Y2015935D01*
X805709Y2015851D01*
G01Y2018101D02*
X805582Y2018185D01*
Y2018351D01*
X805709Y2018435D01*
X805836Y2018351D01*
Y2018185D01*
X805709Y2018101D01*
G01X814516Y2016018D02*
Y2021018D01*
X815782D01*
X816289Y2020768D01*
X816669Y2020435D01*
X816986Y2019935D01*
X817239Y2019351D01*
X817302Y2018518D01*
X817239Y2017685D01*
X816986Y2017101D01*
X816669Y2016601D01*
X816289Y2016268D01*
X815782Y2016018D01*
X814516D01*
G01X821009Y2019351D02*
Y2016018D01*
G01Y2020685D02*
X820882Y2020768D01*
Y2020935D01*
X821009Y2021018D01*
X821136Y2020935D01*
Y2020768D01*
X821009Y2020685D01*
G01X827249Y2016018D02*
Y2019351D01*
G01Y2018768D02*
X826996Y2019101D01*
X826616Y2019268D01*
X826172Y2019351D01*
X825729Y2019185D01*
X825349Y2018851D01*
X825096Y2018351D01*
X824969Y2017685D01*
X825096Y2017018D01*
X825349Y2016518D01*
X825729Y2016185D01*
X826172Y2016018D01*
X826616Y2016101D01*
X826996Y2016351D01*
X827249Y2016685D01*
G01X829309Y2016018D02*
Y2019351D01*
G01Y2018435D02*
X829499Y2018851D01*
X829816Y2019185D01*
X830259Y2019351D01*
X830702Y2019185D01*
X831019Y2018851D01*
X831209Y2018435D01*
Y2016018D01*
G01Y2018435D02*
X831399Y2018851D01*
X831716Y2019185D01*
X832159Y2019351D01*
X832602Y2019185D01*
X832919Y2018851D01*
X833109Y2018351D01*
Y2016018D01*
G01X835359Y2018268D02*
X837386D01*
X837196Y2018851D01*
X836879Y2019185D01*
X836436Y2019351D01*
X835992Y2019268D01*
X835612Y2019018D01*
X835359Y2018435D01*
X835232Y2017935D01*
Y2017435D01*
X835359Y2016935D01*
X835676Y2016435D01*
X836056Y2016101D01*
X836499Y2016018D01*
X836942Y2016185D01*
X837386Y2016685D01*
G01X841409Y2021018D02*
Y2016018D01*
G01X840522Y2019351D02*
X842296D01*
G01X845559Y2018268D02*
X847586D01*
X847396Y2018851D01*
X847079Y2019185D01*
X846636Y2019351D01*
X846192Y2019268D01*
X845812Y2019018D01*
X845559Y2018435D01*
X845432Y2017935D01*
Y2017435D01*
X845559Y2016935D01*
X845876Y2016435D01*
X846256Y2016101D01*
X846699Y2016018D01*
X847142Y2016185D01*
X847586Y2016685D01*
G01X850722Y2016018D02*
Y2019351D01*
G01Y2018685D02*
X851039Y2019018D01*
X851356Y2019268D01*
X851799Y2019351D01*
X852116Y2019268D01*
X852496Y2019018D01*
G01X862569Y2016018D02*
Y2021018D01*
X860226Y2017435D01*
X863392D01*
G01X865009Y2016018D02*
Y2019351D01*
G01Y2018435D02*
X865199Y2018851D01*
X865516Y2019185D01*
X865959Y2019351D01*
X866402Y2019185D01*
X866719Y2018851D01*
X866909Y2018435D01*
Y2016018D01*
G01Y2018435D02*
X867099Y2018851D01*
X867416Y2019185D01*
X867859Y2019351D01*
X868302Y2019185D01*
X868619Y2018851D01*
X868809Y2018351D01*
Y2016018D01*
G01X870109D02*
Y2019351D01*
G01Y2018435D02*
X870299Y2018851D01*
X870616Y2019185D01*
X871059Y2019351D01*
X871502Y2019185D01*
X871819Y2018851D01*
X872009Y2018435D01*
Y2016018D01*
G01Y2018435D02*
X872199Y2018851D01*
X872516Y2019185D01*
X872959Y2019351D01*
X873402Y2019185D01*
X873719Y2018851D01*
X873909Y2018351D01*
Y2016018D01*
G01X880752D02*
Y2021018D01*
X883666Y2016018D01*
Y2021018D01*
G01X886042Y2016018D02*
Y2021018D01*
X887562D01*
X888069Y2020768D01*
X888449Y2020185D01*
X888576Y2019518D01*
X888449Y2018851D01*
X888132Y2018351D01*
X887562Y2018101D01*
X886042D01*
G01X892409Y2021018D02*
Y2016018D01*
G01X890952Y2021018D02*
X893866D01*
G01X896179Y2016018D02*
Y2021018D01*
G01X898839D02*
Y2016018D01*
G01Y2018518D02*
X896179D01*
G01X763265Y1805366D02*
X762765Y1805746D01*
X762515Y1806189D01*
X762432Y1806696D01*
X762599Y1807329D01*
X763015Y1807772D01*
X763515Y1807899D01*
X764015Y1807836D01*
X764432Y1807582D01*
X765265Y1806316D01*
X765849Y1805746D01*
X766682Y1805366D01*
X767432Y1805239D01*
Y1807899D01*
G01X768947Y1816411D02*
X769932Y1810506D01*
X770916Y1816411D01*
X768947D01*
G01X769932Y1806569D02*
Y1810506D01*
G01X770916Y1796726D02*
X769932Y1802632D01*
X768947Y1796726D01*
X770916D01*
G01X769932Y1806569D02*
Y1802632D01*
G01X784499D02*
X769538D01*
G01X784499Y1810506D02*
X769538D01*
G01X771762Y1883246D02*
X785225Y1861705D01*
G01X775727Y1878760D02*
X771762Y1883246D01*
X774058Y1877717D01*
X775727Y1878760D01*
G01X793160Y1783931D02*
X799065Y1784915D01*
X793160Y1785900D01*
Y1783931D01*
G01X784351Y1867821D02*
X788591Y1870471D01*
X787340Y1870585D01*
G01X783948Y1868465D02*
X784754Y1867176D01*
G01X777311Y1885801D02*
X807640Y1892800D01*
G01X782844Y1888088D02*
X777311Y1885801D01*
X783287Y1886170D01*
X782844Y1888088D01*
G01X797049Y1899335D02*
X793864Y1890904D01*
G01X787955Y1873847D02*
X778945Y1874112D01*
G01X785950Y1873980D02*
G03I-2500J0D01*
G01X797957Y1895119D02*
G03I-2501J0D01*
G01X778641Y1983946D02*
X814978Y1992020D01*
G01X784193Y1986187D02*
X778641Y1983946D01*
X784620Y1984267D01*
X784193Y1986187D01*
G01X803972Y1788415D02*
X804352Y1787832D01*
X804858Y1787498D01*
X805428Y1787415D01*
X805935Y1787498D01*
X806442Y1787915D01*
X806758Y1788415D01*
X806822Y1788915D01*
X806695Y1789498D01*
X806252Y1789915D01*
X805808Y1790082D01*
X805238D01*
G01X805808D02*
X806188Y1790332D01*
X806505Y1790748D01*
X806632Y1791248D01*
X806505Y1791748D01*
X806188Y1792165D01*
X805618Y1792415D01*
X805048Y1792332D01*
X804478Y1791998D01*
G01X816782Y1785900D02*
X810876Y1784915D01*
X816782Y1783931D01*
Y1785900D01*
G01X805365Y1784915D02*
X810876D01*
G01X805365D02*
X799065D01*
G01X810876Y1804207D02*
Y1784522D01*
G01X799065Y1804207D02*
Y1784522D01*
G01X799990Y1894626D02*
X800491Y1894143D01*
X801060Y1893932D01*
X801634Y1893979D01*
X802109Y1894175D01*
X802509Y1894694D01*
X802705Y1895253D01*
X802654Y1895754D01*
X802400Y1896294D01*
X801874Y1896600D01*
X801405Y1896663D01*
X800849Y1896535D01*
G01X801405Y1896663D02*
X801719Y1896992D01*
X801934Y1897469D01*
X801945Y1897985D01*
X801709Y1898444D01*
X801307Y1898779D01*
X800695Y1898894D01*
X800158Y1898685D01*
X799678Y1898232D01*
G01X809663Y1993400D02*
X808578Y1998281D01*
X807068Y1994275D01*
X810159Y1994962D01*
G01X804441Y1998642D02*
X801187Y1990236D01*
G01X805314Y1994439D02*
G03I-2500J0D01*
G01X-723776Y2987387D02*
Y-376795D01*
Y-489221D01*
X1782976D01*
Y-376795D01*
Y2987387D01*
X-723776D01*
G01X-69662Y2116817D02*
X-69114Y2116922D01*
X-68487Y2117237D01*
X-68095Y2117762D01*
X-67939Y2118497D01*
X-68095Y2119232D01*
X-68565Y2119862D01*
X-69270Y2120177D01*
X-70054D01*
X-70524Y2120387D01*
X-70915Y2120912D01*
X-71072Y2121647D01*
X-70837Y2122382D01*
X-70289Y2122907D01*
X-69662Y2123117D01*
X-69035Y2122907D01*
X-68487Y2122382D01*
X-68252Y2121647D01*
X-68409Y2120912D01*
X-68800Y2120387D01*
X-69270Y2120177D01*
X-70054D01*
X-70759Y2119862D01*
X-71229Y2119232D01*
X-71385Y2118497D01*
X-71229Y2117762D01*
X-70837Y2117237D01*
X-70210Y2116922D01*
X-69662Y2116817D01*
G01X-63362D02*
Y2123117D01*
X-64302Y2121857D01*
G01Y2116817D02*
X-62422D01*
G01X-57062D02*
X-56514Y2116922D01*
X-55887Y2117237D01*
X-55495Y2117762D01*
X-55339Y2118497D01*
X-55495Y2119232D01*
X-55965Y2119862D01*
X-56670Y2120177D01*
X-57454D01*
X-57924Y2120387D01*
X-58315Y2120912D01*
X-58472Y2121647D01*
X-58237Y2122382D01*
X-57689Y2122907D01*
X-57062Y2123117D01*
X-56435Y2122907D01*
X-55887Y2122382D01*
X-55652Y2121647D01*
X-55809Y2120912D01*
X-56200Y2120387D01*
X-56670Y2120177D01*
X-57454D01*
X-58159Y2119862D01*
X-58629Y2119232D01*
X-58785Y2118497D01*
X-58629Y2117762D01*
X-58237Y2117237D01*
X-57610Y2116922D01*
X-57062Y2116817D01*
G01X-50762D02*
X-50214Y2116922D01*
X-49587Y2117237D01*
X-49195Y2117762D01*
X-49039Y2118497D01*
X-49195Y2119232D01*
X-49665Y2119862D01*
X-50370Y2120177D01*
X-51154D01*
X-51624Y2120387D01*
X-52015Y2120912D01*
X-52172Y2121647D01*
X-51937Y2122382D01*
X-51389Y2122907D01*
X-50762Y2123117D01*
X-50135Y2122907D01*
X-49587Y2122382D01*
X-49352Y2121647D01*
X-49509Y2120912D01*
X-49900Y2120387D01*
X-50370Y2120177D01*
X-51154D01*
X-51859Y2119862D01*
X-52329Y2119232D01*
X-52485Y2118497D01*
X-52329Y2117762D01*
X-51937Y2117237D01*
X-51310Y2116922D01*
X-50762Y2116817D01*
G01X-44462Y2116607D02*
X-44619Y2116712D01*
Y2116922D01*
X-44462Y2117027D01*
X-44305Y2116922D01*
Y2116712D01*
X-44462Y2116607D01*
G01X-39494Y2117552D02*
X-38945Y2117027D01*
X-38319Y2116817D01*
X-37692Y2117027D01*
X-37144Y2117657D01*
X-36752Y2118602D01*
X-36595Y2119547D01*
Y2120702D01*
X-36752Y2121647D01*
X-37144Y2122487D01*
X-37614Y2122907D01*
X-38162Y2123117D01*
X-38789Y2122907D01*
X-39259Y2122487D01*
X-39572Y2121857D01*
X-39729Y2121017D01*
X-39572Y2120282D01*
X-39180Y2119547D01*
X-38710Y2119127D01*
X-38162Y2119022D01*
X-37535Y2119232D01*
X-37065Y2119757D01*
X-36595Y2120702D01*
G01X-31862Y2116817D02*
X-31314Y2116922D01*
X-30687Y2117237D01*
X-30295Y2117762D01*
X-30139Y2118497D01*
X-30295Y2119232D01*
X-30765Y2119862D01*
X-31470Y2120177D01*
X-32254D01*
X-32724Y2120387D01*
X-33115Y2120912D01*
X-33272Y2121647D01*
X-33037Y2122382D01*
X-32489Y2122907D01*
X-31862Y2123117D01*
X-31235Y2122907D01*
X-30687Y2122382D01*
X-30452Y2121647D01*
X-30609Y2120912D01*
X-31000Y2120387D01*
X-31470Y2120177D01*
X-32254D01*
X-32959Y2119862D01*
X-33429Y2119232D01*
X-33585Y2118497D01*
X-33429Y2117762D01*
X-33037Y2117237D01*
X-32410Y2116922D01*
X-31862Y2116817D01*
G01X6705Y-124160D02*
X7332Y-124685D01*
X8037Y-125000D01*
X8663D01*
X9290Y-124685D01*
X9760Y-124160D01*
X9995Y-123425D01*
X9838Y-122690D01*
X9447Y-122060D01*
X8742Y-121640D01*
X7802Y-121430D01*
X7253Y-121010D01*
X7018Y-120275D01*
X7175Y-119540D01*
X7567Y-119015D01*
X8115Y-118700D01*
X8663D01*
X9212Y-118910D01*
X9682Y-119435D01*
G01X13005Y-125000D02*
Y-118700D01*
G01X16295D02*
Y-125000D01*
G01Y-121850D02*
X13005D01*
G01X20010Y-118700D02*
X21890D01*
G01X20950D02*
Y-125000D01*
G01X20010D02*
X21890D01*
G01X28817D02*
X25683D01*
Y-118700D01*
X28817D01*
G01X27563Y-121745D02*
X25683D01*
G01X31748Y-125000D02*
Y-118700D01*
X35352Y-125000D01*
Y-118700D01*
G01X39693Y-126155D02*
X40007Y-124790D01*
G01X46150Y-118700D02*
Y-125000D01*
G01X44348Y-118700D02*
X47952D01*
G01X50492Y-125000D02*
X52450Y-118700D01*
X54408Y-125000D01*
G01X53703Y-122795D02*
X51197D01*
G01X57810Y-118700D02*
X59690D01*
G01X58750D02*
Y-125000D01*
G01X57810D02*
X59690D01*
G01X62700Y-118700D02*
X63797Y-125000D01*
X65050Y-118700D01*
X66303Y-125000D01*
X67400Y-118700D01*
G01X69392Y-125000D02*
X71350Y-118700D01*
X73308Y-125000D01*
G01X72603Y-122795D02*
X70097D01*
G01X75848Y-125000D02*
Y-118700D01*
X79452Y-125000D01*
Y-118700D01*
G01X88683Y-125000D02*
Y-118700D01*
X90642D01*
X91268Y-119015D01*
X91660Y-119435D01*
X91817Y-120275D01*
X91660Y-121115D01*
X91190Y-121640D01*
X90642Y-121955D01*
X88683D01*
G01X90642D02*
X91817Y-125000D01*
G01X96550Y-125210D02*
X96393Y-125105D01*
Y-124895D01*
X96550Y-124790D01*
X96707Y-124895D01*
Y-125105D01*
X96550Y-125210D01*
G01X102850Y-125000D02*
X102223Y-124895D01*
X101675Y-124475D01*
X101205Y-123845D01*
X100892Y-123110D01*
X100735Y-122270D01*
Y-121430D01*
X100892Y-120590D01*
X101205Y-119855D01*
X101675Y-119225D01*
X102223Y-118805D01*
X102850Y-118700D01*
X103477Y-118805D01*
X104025Y-119225D01*
X104495Y-119855D01*
X104808Y-120590D01*
X104965Y-121430D01*
Y-122270D01*
X104808Y-123110D01*
X104495Y-123845D01*
X104025Y-124475D01*
X103477Y-124895D01*
X102850Y-125000D01*
G01X109150Y-125210D02*
X108993Y-125105D01*
Y-124895D01*
X109150Y-124790D01*
X109307Y-124895D01*
Y-125105D01*
X109150Y-125210D01*
G01X117173Y-119225D02*
X116703Y-118910D01*
X116155Y-118700D01*
X115528D01*
X114823Y-119015D01*
X114275Y-119540D01*
X113883Y-120170D01*
X113570Y-121220D01*
X113492Y-122165D01*
X113648Y-123110D01*
X113883Y-123740D01*
X114353Y-124370D01*
X114902Y-124790D01*
X115450Y-125000D01*
X115998D01*
X116547Y-124790D01*
X117017Y-124475D01*
X117408Y-124055D01*
G01X121750Y-125210D02*
X121593Y-125105D01*
Y-124895D01*
X121750Y-124790D01*
X121907Y-124895D01*
Y-125105D01*
X121750Y-125210D01*
G01X6627Y-115000D02*
Y-108700D01*
G01X9603D02*
X6627Y-112585D01*
G01X10073Y-115000D02*
X7958Y-110800D01*
G01X12927Y-108700D02*
Y-113215D01*
X13240Y-114160D01*
X13867Y-114790D01*
X14650Y-115000D01*
X15433Y-114790D01*
X16060Y-114160D01*
X16373Y-113215D01*
Y-108700D01*
G01X22517Y-115000D02*
X19383D01*
Y-108700D01*
X22517D01*
G01X21263Y-111745D02*
X19383D01*
G01X26310Y-108700D02*
X28190D01*
G01X27250D02*
Y-115000D01*
G01X26310D02*
X28190D01*
G01X38205Y-114160D02*
X38832Y-114685D01*
X39537Y-115000D01*
X40163D01*
X40790Y-114685D01*
X41260Y-114160D01*
X41495Y-113425D01*
X41338Y-112690D01*
X40947Y-112060D01*
X40242Y-111640D01*
X39302Y-111430D01*
X38753Y-111010D01*
X38518Y-110275D01*
X38675Y-109540D01*
X39067Y-109015D01*
X39615Y-108700D01*
X40163D01*
X40712Y-108910D01*
X41182Y-109435D01*
G01X44505Y-115000D02*
Y-108700D01*
G01X47795D02*
Y-115000D01*
G01Y-111850D02*
X44505D01*
G01X50492Y-115000D02*
X52450Y-108700D01*
X54408Y-115000D01*
G01X53703Y-112795D02*
X51197D01*
G01X56948Y-115000D02*
Y-108700D01*
X60552Y-115000D01*
Y-108700D01*
G01X69705Y-115000D02*
Y-108700D01*
G01X72995D02*
Y-115000D01*
G01Y-111850D02*
X69705D01*
G01X76005Y-114160D02*
X76632Y-114685D01*
X77337Y-115000D01*
X77963D01*
X78590Y-114685D01*
X79060Y-114160D01*
X79295Y-113425D01*
X79138Y-112690D01*
X78747Y-112060D01*
X78042Y-111640D01*
X77102Y-111430D01*
X76553Y-111010D01*
X76318Y-110275D01*
X76475Y-109540D01*
X76867Y-109015D01*
X77415Y-108700D01*
X77963D01*
X78512Y-108910D01*
X78982Y-109435D01*
G01X83010Y-108700D02*
X84890D01*
G01X83950D02*
Y-115000D01*
G01X83010D02*
X84890D01*
G01X88292D02*
X90250Y-108700D01*
X92208Y-115000D01*
G01X91503Y-112795D02*
X88997D01*
G01X94748Y-115000D02*
Y-108700D01*
X98352Y-115000D01*
Y-108700D01*
G01X103320Y-111850D02*
X104887D01*
Y-113740D01*
X104417Y-114370D01*
X103868Y-114790D01*
X103085Y-115000D01*
X102302Y-114790D01*
X101753Y-114370D01*
X101283Y-113740D01*
X100970Y-113005D01*
X100813Y-112165D01*
Y-111430D01*
X100970Y-110800D01*
X101283Y-110065D01*
X101753Y-109435D01*
X102223Y-109015D01*
X102850Y-108700D01*
X103398D01*
X104025Y-108910D01*
X104495Y-109330D01*
G01X108993Y-116155D02*
X109307Y-114790D01*
G01X115450Y-108700D02*
Y-115000D01*
G01X113648Y-108700D02*
X117252D01*
G01X119792Y-115000D02*
X121750Y-108700D01*
X123708Y-115000D01*
G01X123003Y-112795D02*
X120497D01*
G01X128050Y-115000D02*
X127423Y-114895D01*
X126875Y-114475D01*
X126405Y-113845D01*
X126092Y-113110D01*
X125935Y-112270D01*
Y-111430D01*
X126092Y-110590D01*
X126405Y-109855D01*
X126875Y-109225D01*
X127423Y-108805D01*
X128050Y-108700D01*
X128677Y-108805D01*
X129225Y-109225D01*
X129695Y-109855D01*
X130008Y-110590D01*
X130165Y-111430D01*
Y-112270D01*
X130008Y-113110D01*
X129695Y-113845D01*
X129225Y-114475D01*
X128677Y-114895D01*
X128050Y-115000D01*
G01X140650D02*
Y-112165D01*
X139083Y-108700D01*
G01X142217D02*
X140650Y-112165D01*
G01X145227Y-108700D02*
Y-113215D01*
X145540Y-114160D01*
X146167Y-114790D01*
X146950Y-115000D01*
X147733Y-114790D01*
X148360Y-114160D01*
X148673Y-113215D01*
Y-108700D01*
G01X151292Y-115000D02*
X153250Y-108700D01*
X155208Y-115000D01*
G01X154503Y-112795D02*
X151997D01*
G01X157748Y-115000D02*
Y-108700D01*
X161352Y-115000D01*
Y-108700D01*
G01X30650Y-92300D02*
X28130Y-91883D01*
X25925Y-90217D01*
X24035Y-87717D01*
X22775Y-84800D01*
X22145Y-81467D01*
Y-78133D01*
X22775Y-74800D01*
X24035Y-71883D01*
X25925Y-69384D01*
X28130Y-67717D01*
X30650Y-67300D01*
X33170Y-67717D01*
X35375Y-69384D01*
X37265Y-71883D01*
X38525Y-74800D01*
X39155Y-78133D01*
Y-81467D01*
X38525Y-84800D01*
X37265Y-87717D01*
X35375Y-90217D01*
X33170Y-91883D01*
X30650Y-92300D01*
G01X33170Y-85633D02*
X36950Y-92300D01*
G01X50495Y-75634D02*
Y-87300D01*
X51755Y-90217D01*
X53645Y-91883D01*
X55850Y-92300D01*
X58055Y-91883D01*
X59945Y-90217D01*
X61205Y-87300D01*
G01Y-92300D02*
Y-75634D01*
G01X86720Y-92300D02*
Y-75634D01*
G01Y-78550D02*
X85460Y-76884D01*
X83570Y-76050D01*
X81365Y-75634D01*
X79160Y-76467D01*
X77270Y-78133D01*
X76010Y-80634D01*
X75380Y-83967D01*
X76010Y-87300D01*
X77270Y-89801D01*
X79160Y-91467D01*
X81365Y-92300D01*
X83570Y-91883D01*
X85460Y-90634D01*
X86720Y-88967D01*
G01X100895Y-92300D02*
Y-75634D01*
G01Y-79800D02*
X102155Y-77717D01*
X104045Y-76050D01*
X106565Y-75634D01*
X108770Y-76050D01*
X110660Y-77717D01*
X111605Y-80634D01*
Y-92300D01*
G01X131450Y-67300D02*
Y-92300D01*
G01X127040Y-75634D02*
X135860D01*
G01X162320Y-92300D02*
Y-75634D01*
G01Y-78550D02*
X161060Y-76884D01*
X159170Y-76050D01*
X156965Y-75634D01*
X154760Y-76467D01*
X152870Y-78133D01*
X151610Y-80634D01*
X150980Y-83967D01*
X151610Y-87300D01*
X152870Y-89801D01*
X154760Y-91467D01*
X156965Y-92300D01*
X159170Y-91883D01*
X161060Y-90634D01*
X162320Y-88967D01*
G01X6548Y-105000D02*
Y-98700D01*
X10152Y-105000D01*
Y-98700D01*
G01X14650Y-105000D02*
X14023Y-104895D01*
X13475Y-104475D01*
X13005Y-103845D01*
X12692Y-103110D01*
X12535Y-102270D01*
Y-101430D01*
X12692Y-100590D01*
X13005Y-99855D01*
X13475Y-99225D01*
X14023Y-98805D01*
X14650Y-98700D01*
X15277Y-98805D01*
X15825Y-99225D01*
X16295Y-99855D01*
X16608Y-100590D01*
X16765Y-101430D01*
Y-102270D01*
X16608Y-103110D01*
X16295Y-103845D01*
X15825Y-104475D01*
X15277Y-104895D01*
X14650Y-105000D01*
G01X20950Y-105210D02*
X20793Y-105105D01*
Y-104895D01*
X20950Y-104790D01*
X21107Y-104895D01*
Y-105105D01*
X20950Y-105210D01*
G01X27250Y-105000D02*
Y-98700D01*
X26310Y-99960D01*
G01Y-105000D02*
X28190D01*
G01X33550D02*
X34098Y-104895D01*
X34725Y-104580D01*
X35117Y-104055D01*
X35273Y-103320D01*
X35117Y-102585D01*
X34647Y-101955D01*
X33942Y-101640D01*
X33158D01*
X32688Y-101430D01*
X32297Y-100905D01*
X32140Y-100170D01*
X32375Y-99435D01*
X32923Y-98910D01*
X33550Y-98700D01*
X34177Y-98910D01*
X34725Y-99435D01*
X34960Y-100170D01*
X34803Y-100905D01*
X34412Y-101430D01*
X33942Y-101640D01*
X33158D01*
X32453Y-101955D01*
X31983Y-102585D01*
X31827Y-103320D01*
X31983Y-104055D01*
X32375Y-104580D01*
X33002Y-104895D01*
X33550Y-105000D01*
G01X39850D02*
X40398Y-104895D01*
X41025Y-104580D01*
X41417Y-104055D01*
X41573Y-103320D01*
X41417Y-102585D01*
X40947Y-101955D01*
X40242Y-101640D01*
X39458D01*
X38988Y-101430D01*
X38597Y-100905D01*
X38440Y-100170D01*
X38675Y-99435D01*
X39223Y-98910D01*
X39850Y-98700D01*
X40477Y-98910D01*
X41025Y-99435D01*
X41260Y-100170D01*
X41103Y-100905D01*
X40712Y-101430D01*
X40242Y-101640D01*
X39458D01*
X38753Y-101955D01*
X38283Y-102585D01*
X38127Y-103320D01*
X38283Y-104055D01*
X38675Y-104580D01*
X39302Y-104895D01*
X39850Y-105000D01*
G01X45993Y-106155D02*
X46307Y-104790D01*
G01X50100Y-98700D02*
X51197Y-105000D01*
X52450Y-98700D01*
X53703Y-105000D01*
X54800Y-98700D01*
G01X60317Y-105000D02*
X57183D01*
Y-98700D01*
X60317D01*
G01X59063Y-101745D02*
X57183D01*
G01X63248Y-105000D02*
Y-98700D01*
X66852Y-105000D01*
Y-98700D01*
G01X76005Y-105000D02*
Y-98700D01*
G01X79295D02*
Y-105000D01*
G01Y-101850D02*
X76005D01*
G01X81600Y-98700D02*
X82697Y-105000D01*
X83950Y-98700D01*
X85203Y-105000D01*
X86300Y-98700D01*
G01X88292Y-105000D02*
X90250Y-98700D01*
X92208Y-105000D01*
G01X91503Y-102795D02*
X88997D01*
G01X101362Y-99750D02*
X101832Y-99120D01*
X102380Y-98805D01*
X103007Y-98700D01*
X103790Y-98910D01*
X104338Y-99435D01*
X104495Y-100065D01*
X104417Y-100695D01*
X104103Y-101220D01*
X102537Y-102270D01*
X101832Y-103005D01*
X101362Y-104055D01*
X101205Y-105000D01*
X104495D01*
G01X107348D02*
Y-98700D01*
X110952Y-105000D01*
Y-98700D01*
G01X113727Y-105000D02*
Y-98700D01*
X115293D01*
X115920Y-99015D01*
X116390Y-99435D01*
X116782Y-100065D01*
X117095Y-100800D01*
X117173Y-101850D01*
X117095Y-102900D01*
X116782Y-103635D01*
X116390Y-104265D01*
X115920Y-104685D01*
X115293Y-105000D01*
X113727D01*
G01X126483D02*
Y-98700D01*
X128442D01*
X129068Y-99015D01*
X129460Y-99435D01*
X129617Y-100275D01*
X129460Y-101115D01*
X128990Y-101640D01*
X128442Y-101955D01*
X126483D01*
G01X128442D02*
X129617Y-105000D01*
G01X132627D02*
Y-98700D01*
X134193D01*
X134820Y-99015D01*
X135290Y-99435D01*
X135682Y-100065D01*
X135995Y-100800D01*
X136073Y-101850D01*
X135995Y-102900D01*
X135682Y-103635D01*
X135290Y-104265D01*
X134820Y-104685D01*
X134193Y-105000D01*
X132627D01*
G01X140650Y-105210D02*
X140493Y-105105D01*
Y-104895D01*
X140650Y-104790D01*
X140807Y-104895D01*
Y-105105D01*
X140650Y-105210D01*
G01X202000Y-72000D02*
Y-80000D01*
X206000D01*
G01X213800D02*
Y-74667D01*
G01Y-75600D02*
X213400Y-75067D01*
X212800Y-74800D01*
X212100Y-74667D01*
X211400Y-74933D01*
X210800Y-75467D01*
X210400Y-76267D01*
X210200Y-77333D01*
X210400Y-78400D01*
X210800Y-79200D01*
X211400Y-79733D01*
X212100Y-80000D01*
X212800Y-79867D01*
X213400Y-79467D01*
X213800Y-78934D01*
G01X217900Y-82400D02*
X218500Y-82667D01*
X219300Y-82400D01*
X219800Y-81867D01*
X220200Y-81200D01*
X220800Y-79067D01*
X222100Y-74667D01*
G01X218900D02*
X220800Y-79067D01*
G01X226500Y-76400D02*
X229700D01*
X229400Y-75467D01*
X228900Y-74933D01*
X228200Y-74667D01*
X227500Y-74800D01*
X226900Y-75200D01*
X226500Y-76133D01*
X226300Y-76934D01*
Y-77733D01*
X226500Y-78533D01*
X227000Y-79333D01*
X227600Y-79867D01*
X228300Y-80000D01*
X229000Y-79733D01*
X229700Y-78934D01*
G01X234600Y-80000D02*
Y-74667D01*
G01Y-75733D02*
X235100Y-75200D01*
X235600Y-74800D01*
X236300Y-74667D01*
X236800Y-74800D01*
X237400Y-75200D01*
G01X225500Y-122000D02*
Y-130000D01*
G01X223200Y-122000D02*
X227800D01*
G01X233500Y-124667D02*
Y-130000D01*
G01Y-122533D02*
X233300Y-122400D01*
Y-122133D01*
X233500Y-122000D01*
X233700Y-122133D01*
Y-122400D01*
X233500Y-122533D01*
G01X239800Y-130000D02*
Y-124667D01*
G01Y-126000D02*
X240200Y-125333D01*
X240800Y-124800D01*
X241600Y-124667D01*
X242300Y-124800D01*
X242900Y-125333D01*
X243200Y-126267D01*
Y-130000D01*
G01X251300D02*
Y-124667D01*
G01Y-125600D02*
X250900Y-125067D01*
X250300Y-124800D01*
X249600Y-124667D01*
X248900Y-124933D01*
X248300Y-125467D01*
X247900Y-126267D01*
X247700Y-127333D01*
X247900Y-128400D01*
X248300Y-129200D01*
X248900Y-129733D01*
X249600Y-130000D01*
X250300Y-129867D01*
X250900Y-129467D01*
X251300Y-128934D01*
G01X221000Y-105000D02*
Y-97000D01*
X223400D01*
X224200Y-97400D01*
X224800Y-98333D01*
X225000Y-99400D01*
X224800Y-100467D01*
X224300Y-101267D01*
X223400Y-101667D01*
X221000D01*
G01X228500Y-105000D02*
X231000Y-97000D01*
X233500Y-105000D01*
G01X232600Y-102200D02*
X229400D01*
G01X236700Y-105000D02*
Y-97000D01*
X241300Y-105000D01*
Y-97000D01*
G01X249000Y-105000D02*
X245000D01*
Y-97000D01*
X249000D01*
G01X247400Y-100867D02*
X245000D01*
G01X253000Y-97000D02*
Y-105000D01*
X257000D01*
G01X328600Y-123333D02*
X329200Y-122533D01*
X329900Y-122133D01*
X330700Y-122000D01*
X331700Y-122267D01*
X332400Y-122933D01*
X332600Y-123733D01*
X332500Y-124534D01*
X332100Y-125200D01*
X330100Y-126533D01*
X329200Y-127467D01*
X328600Y-128800D01*
X328400Y-130000D01*
X332600D01*
G01X338500Y-122000D02*
X337700Y-122267D01*
X337100Y-122933D01*
X336700Y-123733D01*
X336400Y-124800D01*
X336300Y-126000D01*
X336400Y-127200D01*
X336700Y-128267D01*
X337100Y-129067D01*
X337700Y-129733D01*
X338500Y-130000D01*
X339300Y-129733D01*
X339900Y-129067D01*
X340300Y-128267D01*
X340600Y-127200D01*
X340700Y-126000D01*
X340600Y-124800D01*
X340300Y-123733D01*
X339900Y-122933D01*
X339300Y-122267D01*
X338500Y-122000D01*
G01X346500Y-130000D02*
Y-122000D01*
X345300Y-123600D01*
G01Y-130000D02*
X347700D01*
G01X352300Y-128400D02*
X352900Y-129333D01*
X353700Y-129867D01*
X354600Y-130000D01*
X355400Y-129867D01*
X356200Y-129200D01*
X356700Y-128400D01*
X356800Y-127600D01*
X356600Y-126667D01*
X355900Y-126000D01*
X355200Y-125733D01*
X354300D01*
G01X355200D02*
X355800Y-125333D01*
X356300Y-124667D01*
X356500Y-123867D01*
X356300Y-123067D01*
X355800Y-122400D01*
X354900Y-122000D01*
X354000Y-122133D01*
X353100Y-122667D01*
G01X360700Y-130267D02*
X364300Y-122000D01*
G01X370500D02*
X369700Y-122267D01*
X369100Y-122933D01*
X368700Y-123733D01*
X368400Y-124800D01*
X368300Y-126000D01*
X368400Y-127200D01*
X368700Y-128267D01*
X369100Y-129067D01*
X369700Y-129733D01*
X370500Y-130000D01*
X371300Y-129733D01*
X371900Y-129067D01*
X372300Y-128267D01*
X372600Y-127200D01*
X372700Y-126000D01*
X372600Y-124800D01*
X372300Y-123733D01*
X371900Y-122933D01*
X371300Y-122267D01*
X370500Y-122000D01*
G01X378500Y-130000D02*
Y-122000D01*
X377300Y-123600D01*
G01Y-130000D02*
X379700D01*
G01X384700Y-130267D02*
X388300Y-122000D01*
G01X394500D02*
X393700Y-122267D01*
X393100Y-122933D01*
X392700Y-123733D01*
X392400Y-124800D01*
X392300Y-126000D01*
X392400Y-127200D01*
X392700Y-128267D01*
X393100Y-129067D01*
X393700Y-129733D01*
X394500Y-130000D01*
X395300Y-129733D01*
X395900Y-129067D01*
X396300Y-128267D01*
X396600Y-127200D01*
X396700Y-126000D01*
X396600Y-124800D01*
X396300Y-123733D01*
X395900Y-122933D01*
X395300Y-122267D01*
X394500Y-122000D01*
G01X400800Y-129067D02*
X401500Y-129733D01*
X402300Y-130000D01*
X403100Y-129733D01*
X403800Y-128934D01*
X404300Y-127733D01*
X404500Y-126533D01*
Y-125067D01*
X404300Y-123867D01*
X403800Y-122800D01*
X403200Y-122267D01*
X402500Y-122000D01*
X401700Y-122267D01*
X401100Y-122800D01*
X400700Y-123600D01*
X400500Y-124667D01*
X400700Y-125600D01*
X401200Y-126533D01*
X401800Y-127067D01*
X402500Y-127200D01*
X403300Y-126934D01*
X403900Y-126267D01*
X404500Y-125067D01*
G01X328300Y-105000D02*
Y-97000D01*
X330300D01*
X331100Y-97400D01*
X331700Y-97933D01*
X332200Y-98733D01*
X332600Y-99667D01*
X332700Y-101000D01*
X332600Y-102333D01*
X332200Y-103267D01*
X331700Y-104067D01*
X331100Y-104600D01*
X330300Y-105000D01*
X328300D01*
G01X336000D02*
X338500Y-97000D01*
X341000Y-105000D01*
G01X340100Y-102200D02*
X336900D01*
G01X346500Y-97000D02*
Y-105000D01*
G01X344200Y-97000D02*
X348800D01*
G01X352600Y-101667D02*
X353300Y-100733D01*
X353900Y-100200D01*
X354700Y-99933D01*
X355400Y-100200D01*
X355900Y-100733D01*
X356300Y-101533D01*
X356400Y-102467D01*
X356300Y-103267D01*
X355900Y-104067D01*
X355300Y-104733D01*
X354600Y-105000D01*
X353800Y-104733D01*
X353100Y-103934D01*
X352700Y-102733D01*
X352600Y-101400D01*
X352800Y-99667D01*
X353100Y-98733D01*
X353600Y-97800D01*
X354300Y-97133D01*
X355000Y-97000D01*
X355700Y-97267D01*
X356200Y-97933D01*
G01X359900Y-105000D02*
Y-97000D01*
X362500Y-103667D01*
X365100Y-97000D01*
Y-105000D01*
G01X370500Y-97000D02*
Y-105000D01*
G01X368200Y-97000D02*
X372800D01*
G01X379300Y-100733D02*
X379700Y-100333D01*
X380000Y-99667D01*
X380200Y-98733D01*
X380000Y-97933D01*
X379600Y-97400D01*
X378900Y-97000D01*
X376200D01*
Y-105000D01*
X379500D01*
X380200Y-104467D01*
X380600Y-103667D01*
X380800Y-102733D01*
X380600Y-101800D01*
X380000Y-101000D01*
X379300Y-100733D01*
X376200D01*
G01X386500Y-105000D02*
X387200Y-104867D01*
X388000Y-104467D01*
X388500Y-103800D01*
X388700Y-102867D01*
X388500Y-101934D01*
X387900Y-101133D01*
X387000Y-100733D01*
X386000D01*
X385400Y-100467D01*
X384900Y-99800D01*
X384700Y-98867D01*
X385000Y-97933D01*
X385700Y-97267D01*
X386500Y-97000D01*
X387300Y-97267D01*
X388000Y-97933D01*
X388300Y-98867D01*
X388100Y-99800D01*
X387600Y-100467D01*
X387000Y-100733D01*
X386000D01*
X385100Y-101133D01*
X384500Y-101934D01*
X384300Y-102867D01*
X384500Y-103800D01*
X385000Y-104467D01*
X385800Y-104867D01*
X386500Y-105000D01*
G01X394500D02*
X395200Y-104867D01*
X396000Y-104467D01*
X396500Y-103800D01*
X396700Y-102867D01*
X396500Y-101934D01*
X395900Y-101133D01*
X395000Y-100733D01*
X394000D01*
X393400Y-100467D01*
X392900Y-99800D01*
X392700Y-98867D01*
X393000Y-97933D01*
X393700Y-97267D01*
X394500Y-97000D01*
X395300Y-97267D01*
X396000Y-97933D01*
X396300Y-98867D01*
X396100Y-99800D01*
X395600Y-100467D01*
X395000Y-100733D01*
X394000D01*
X393100Y-101133D01*
X392500Y-101934D01*
X392300Y-102867D01*
X392500Y-103800D01*
X393000Y-104467D01*
X393800Y-104867D01*
X394500Y-105000D01*
G01X400000D02*
X402500Y-97000D01*
X405000Y-105000D01*
G01X404100Y-102200D02*
X400900D01*
G01X410500Y-97000D02*
X409700Y-97267D01*
X409100Y-97933D01*
X408700Y-98733D01*
X408400Y-99800D01*
X408300Y-101000D01*
X408400Y-102200D01*
X408700Y-103267D01*
X409100Y-104067D01*
X409700Y-104733D01*
X410500Y-105000D01*
X411300Y-104733D01*
X411900Y-104067D01*
X412300Y-103267D01*
X412600Y-102200D01*
X412700Y-101000D01*
X412600Y-99800D01*
X412300Y-98733D01*
X411900Y-97933D01*
X411300Y-97267D01*
X410500Y-97000D01*
G01X350500Y-72000D02*
Y-80000D01*
G01X348200Y-72000D02*
X352800D01*
G01X356600Y-76667D02*
X357300Y-75733D01*
X357900Y-75200D01*
X358700Y-74933D01*
X359400Y-75200D01*
X359900Y-75733D01*
X360300Y-76533D01*
X360400Y-77467D01*
X360300Y-78267D01*
X359900Y-79067D01*
X359300Y-79733D01*
X358600Y-80000D01*
X357800Y-79733D01*
X357100Y-78934D01*
X356700Y-77733D01*
X356600Y-76400D01*
X356800Y-74667D01*
X357100Y-73733D01*
X357600Y-72800D01*
X358300Y-72133D01*
X359000Y-72000D01*
X359700Y-72267D01*
X360200Y-72933D01*
G01X363900Y-80000D02*
Y-72000D01*
X366500Y-78667D01*
X369100Y-72000D01*
Y-80000D01*
G01X375100Y-76000D02*
X377100D01*
Y-78400D01*
X376500Y-79200D01*
X375800Y-79733D01*
X374800Y-80000D01*
X373800Y-79733D01*
X373100Y-79200D01*
X372500Y-78400D01*
X372100Y-77467D01*
X371900Y-76400D01*
Y-75467D01*
X372100Y-74667D01*
X372500Y-73733D01*
X373100Y-72933D01*
X373700Y-72400D01*
X374500Y-72000D01*
X375200D01*
X376000Y-72267D01*
X376600Y-72800D01*
G01X379500Y-82667D02*
X385500D01*
G01X388500Y-80000D02*
Y-72000D01*
X390900D01*
X391700Y-72400D01*
X392300Y-73333D01*
X392500Y-74400D01*
X392300Y-75467D01*
X391800Y-76267D01*
X390900Y-76667D01*
X388500D01*
G01X396300Y-80000D02*
Y-72000D01*
X398300D01*
X399100Y-72400D01*
X399700Y-72933D01*
X400200Y-73733D01*
X400600Y-74667D01*
X400700Y-76000D01*
X400600Y-77333D01*
X400200Y-78267D01*
X399700Y-79067D01*
X399100Y-79600D01*
X398300Y-80000D01*
X396300D01*
G01X407300Y-75733D02*
X407700Y-75333D01*
X408000Y-74667D01*
X408200Y-73733D01*
X408000Y-72933D01*
X407600Y-72400D01*
X406900Y-72000D01*
X404200D01*
Y-80000D01*
X407500D01*
X408200Y-79467D01*
X408600Y-78667D01*
X408800Y-77733D01*
X408600Y-76800D01*
X408000Y-76000D01*
X407300Y-75733D01*
X404200D01*
G01X411500Y-82667D02*
X417500D01*
G01X420000Y-80000D02*
X422500Y-72000D01*
X425000Y-80000D01*
G01X424100Y-77200D02*
X420900D01*
G01X427500Y-82667D02*
X433500D01*
G01X439300Y-75733D02*
X439700Y-75333D01*
X440000Y-74667D01*
X440200Y-73733D01*
X440000Y-72933D01*
X439600Y-72400D01*
X438900Y-72000D01*
X436200D01*
Y-80000D01*
X439500D01*
X440200Y-79467D01*
X440600Y-78667D01*
X440800Y-77733D01*
X440600Y-76800D01*
X440000Y-76000D01*
X439300Y-75733D01*
X436200D01*
G01X444300Y-80000D02*
Y-72000D01*
X446300D01*
X447100Y-72400D01*
X447700Y-72933D01*
X448200Y-73733D01*
X448600Y-74667D01*
X448700Y-76000D01*
X448600Y-77333D01*
X448200Y-78267D01*
X447700Y-79067D01*
X447100Y-79600D01*
X446300Y-80000D01*
X444300D01*
G01X443000Y-130000D02*
X445500Y-122000D01*
X448000Y-130000D01*
G01X447100Y-127200D02*
X443900D01*
G01X473000Y-130000D02*
Y-122000D01*
X471800Y-123600D01*
G01Y-130000D02*
X474200D01*
G01X479100Y-126667D02*
X479800Y-125733D01*
X480400Y-125200D01*
X481200Y-124933D01*
X481900Y-125200D01*
X482400Y-125733D01*
X482800Y-126533D01*
X482900Y-127467D01*
X482800Y-128267D01*
X482400Y-129067D01*
X481800Y-129733D01*
X481100Y-130000D01*
X480300Y-129733D01*
X479600Y-128934D01*
X479200Y-127733D01*
X479100Y-126400D01*
X479300Y-124667D01*
X479600Y-123733D01*
X480100Y-122800D01*
X480800Y-122133D01*
X481500Y-122000D01*
X482200Y-122267D01*
X482700Y-122933D01*
G01X491139Y1015941D02*
X490509Y1016411D01*
X490194Y1016959D01*
X490089Y1017586D01*
X490299Y1018369D01*
X490824Y1018917D01*
X491454Y1019074D01*
X492084Y1018996D01*
X492609Y1018682D01*
X493659Y1017116D01*
X494394Y1016411D01*
X495444Y1015941D01*
X496389Y1015784D01*
Y1019074D01*
G01X490089Y1023729D02*
X490299Y1023102D01*
X490824Y1022632D01*
X491454Y1022319D01*
X492294Y1022084D01*
X493239Y1022006D01*
X494184Y1022084D01*
X495024Y1022319D01*
X495654Y1022632D01*
X496179Y1023102D01*
X496389Y1023729D01*
X496179Y1024356D01*
X495654Y1024826D01*
X495024Y1025139D01*
X494184Y1025374D01*
X493239Y1025452D01*
X492294Y1025374D01*
X491454Y1025139D01*
X490824Y1024826D01*
X490299Y1024356D01*
X490089Y1023729D01*
G01X496389Y1030029D02*
X496284Y1030577D01*
X495969Y1031204D01*
X495444Y1031596D01*
X494709Y1031752D01*
X493974Y1031596D01*
X493344Y1031126D01*
X493029Y1030421D01*
Y1029637D01*
X492819Y1029167D01*
X492294Y1028776D01*
X491559Y1028619D01*
X490824Y1028854D01*
X490299Y1029402D01*
X490089Y1030029D01*
X490299Y1030656D01*
X490824Y1031204D01*
X491559Y1031439D01*
X492294Y1031282D01*
X492819Y1030891D01*
X493029Y1030421D01*
Y1029637D01*
X493344Y1028932D01*
X493974Y1028462D01*
X494709Y1028306D01*
X495444Y1028462D01*
X495969Y1028854D01*
X496284Y1029481D01*
X496389Y1030029D01*
G01X493764Y1034841D02*
X493029Y1035389D01*
X492609Y1035859D01*
X492399Y1036486D01*
X492609Y1037034D01*
X493029Y1037426D01*
X493659Y1037739D01*
X494394Y1037817D01*
X495024Y1037739D01*
X495654Y1037426D01*
X496179Y1036956D01*
X496389Y1036407D01*
X496179Y1035781D01*
X495549Y1035232D01*
X494604Y1034919D01*
X493554Y1034841D01*
X492189Y1034997D01*
X491454Y1035232D01*
X490719Y1035624D01*
X490194Y1036172D01*
X490089Y1036721D01*
X490299Y1037269D01*
X490824Y1037661D01*
G01X493764Y1041141D02*
X493029Y1041689D01*
X492609Y1042159D01*
X492399Y1042786D01*
X492609Y1043334D01*
X493029Y1043726D01*
X493659Y1044039D01*
X494394Y1044117D01*
X495024Y1044039D01*
X495654Y1043726D01*
X496179Y1043256D01*
X496389Y1042707D01*
X496179Y1042081D01*
X495549Y1041532D01*
X494604Y1041219D01*
X493554Y1041141D01*
X492189Y1041297D01*
X491454Y1041532D01*
X490719Y1041924D01*
X490194Y1042472D01*
X490089Y1043021D01*
X490299Y1043569D01*
X490824Y1043961D01*
G01X496599Y1048929D02*
X496494Y1048772D01*
X496284D01*
X496179Y1048929D01*
X496284Y1049086D01*
X496494D01*
X496599Y1048929D01*
G01X496389Y1055229D02*
X490089D01*
X491349Y1054289D01*
G01X496389D02*
Y1056169D01*
G01Y1062469D02*
X490089D01*
X494604Y1059571D01*
Y1063487D01*
G01X730168Y2032159D02*
X974577D01*
Y1748144D01*
X730168D01*
Y2032159D01*
G01X777412Y1883734D02*
G03I-5906J0D01*
G01X778829Y1982237D02*
G03I-7874J0D01*
G01X785680Y1810506D02*
X795128D01*
G02Y1802632I0J-3937D01*
G01X785680D01*
G01X814813Y1810506D02*
X824262D01*
G01X814813D02*
G03Y1802632I0J-3937D01*
G01X824262D01*
M02*
